FILE_TYPE = MACRO_DRAWING;
SET COLOR_WIRE YELLOW;
SET COLOR_PROP ORANGE;
SET COLOR_DOT WHITE;
SET COLOR_ARC YELLOW;
SET COLOR_BODY GREEN;
SET COLOR_NOTE PURPLE;
SET PROP_DISPLAY VALUE;
SET PAGE_NUMBER P183;
FORCEADD OFFPAGE..1
(-8050 1400);
FORCEPROP 2 LAST $XR1 208 
J 0
(-8422 1400);
DISPLAY 0.638298 (-8422 1400);
PAINT MONO (-8422 1400);
FORCEPROP 2 LAST $XR0 207 
J 0
(-8302 1400);
DISPLAY 0.638298 (-8302 1400);
PAINT MONO (-8302 1400);
FORCEPROP 2 LAST CDS_LIB standard
J 0
(-8050 1400);
DISPLAY INVISIBLE (-8050 1400);
FORCEPROP 1 LAST OFFPAGE TRUE
J 0
(-7725 1275);
DISPLAY 0.872340 (-7725 1275);
PAINT GREEN (-7725 1275);
DISPLAY INVISIBLE (-7725 1275);
FORCEPROP 1 LAST COMMENT_BODY TRUE
J 0
(-7925 1300);
DISPLAY 0.872340 (-7925 1300);
PAINT GREEN (-7925 1300);
DISPLAY INVISIBLE (-7925 1300);
FORCEPROP 2 LAST PATH I1
J 0
(-8300 1450);
DISPLAY 0.680851 (-8300 1450);
DISPLAY INVISIBLE (-8300 1450);
FORCEADD UNIVERSAL_GND..1
(-7500 1025);
FORCEPROP 3 LASTPIN (-7500 1075) SIG_NAME GND\g
J 0
(-7490 1085);
DISPLAY 0.659574 (-7490 1085);
PAINT MONO (-7490 1085);
DISPLAY INVISIBLE (-7490 1085);
FORCEPROP 2 LAST CDS_LIB pure_quanta_power
J 0
(-7500 1025);
DISPLAY INVISIBLE (-7500 1025);
FORCEPROP 1 LAST HDL_POWER GND
J 1
(-7475 950);
DISPLAY 0.872340 (-7475 950);
PAINT GREEN (-7475 950);
DISPLAY INVISIBLE (-7475 950);
FORCEPROP 1 LAST PATH I10
J 0
(-7425 1025);
DISPLAY 0.872340 (-7425 1025);
PAINT AQUA (-7425 1025);
DISPLAY INVISIBLE (-7425 1025);
FORCEADD Q_RES..1
(-7175 1200);
FORCEPROP 1 LAST LOCATION PR134
J 0
(-7175 1250);
DISPLAY 0.489362 (-7175 1250);
PAINT SKYBLUE (-7175 1250);
FORCEPROP 0 LAST $SEC 1
J 0
(-7175 1275);
DISPLAY 0.680851 (-7175 1275);
PAINT MONO (-7175 1275);
DISPLAY INVISIBLE (-7175 1275);
FORCEPROP 0 LAST CDS_SEC 1
J 0
(-7175 1275);
DISPLAY 1.021277 (-7175 1275);
DISPLAY INVISIBLE (-7175 1275);
FORCEPROP 1 LASTPIN (-7275 1200) $PN 1
J 0
(-7263 1212);
DISPLAY 0.489362 (-7263 1212);
PAINT MONO (-7263 1212);
FORCEPROP 1 LASTPIN (-7075 1200) $PN 2
J 0
(-7113 1212);
DISPLAY 0.489362 (-7113 1212);
PAINT MONO (-7113 1212);
FORCEPROP 1 LAST PACK_TYPE 0402LF
J 0
(-7075 1150);
DISPLAY 0.489362 (-7075 1150);
PAINT SKYBLUE (-7075 1150);
FORCEPROP 1 LAST MATERIAL EMPTY
J 0
(-7475 1100);
DISPLAY 0.489362 (-7475 1100);
PAINT RED (-7475 1100);
FORCEPROP 1 LAST TOLERANCE 1%
J 0
(-7050 1225);
DISPLAY 0.489362 (-7050 1225);
PAINT SKYBLUE (-7050 1225);
FORCEPROP 1 LAST VALUE 4.87K
J 2
(-7250 1225);
DISPLAY 0.489362 (-7250 1225);
PAINT SKYBLUE (-7250 1225);
FORCEPROP 1 LAST WATTAGE 1/16W
J 0
(-7075 1100);
DISPLAY 0.489362 (-7075 1100);
PAINT SKYBLUE (-7075 1100);
FORCEPROP 2 LAST CDS_LIB pure_quanta
J 0
(-7175 1200);
DISPLAY INVISIBLE (-7175 1200);
FORCEPROP 1 LAST PATH I11
J 0
(-7225 1350);
DISPLAY 0.978723 (-7225 1350);
PAINT WHITE (-7225 1350);
DISPLAY INVISIBLE (-7225 1350);
FORCEPROP 1 LAST PART_NUMBER CS24872FB01
J 0
(-7475 1150);
DISPLAY 0.489362 (-7475 1150);
PAINT SKYBLUE (-7475 1150);
DISPLAY INVISIBLE (-7475 1150);
FORCEADD OFFPAGE..2
R 2
(-7150 1500);
FORCEPROP 2 LAST $XR0 207 
J 0
(-7435 1500);
DISPLAY 0.638298 (-7435 1500);
PAINT MONO (-7435 1500);
FORCEPROP 2 LAST CDS_LIB standard
J 2
(-7150 1500);
DISPLAY INVISIBLE (-7150 1500);
FORCEPROP 1 LAST OFFPAGE TRUE
J 2
(-7475 1375);
DISPLAY 0.872340 (-7475 1375);
PAINT GREEN (-7475 1375);
DISPLAY INVISIBLE (-7475 1375);
FORCEPROP 1 LAST COMMENT_BODY TRUE
J 2
(-7105 1405);
DISPLAY 0.872340 (-7105 1405);
PAINT GREEN (-7105 1405);
DISPLAY INVISIBLE (-7105 1405);
FORCEPROP 2 LAST PATH I12
J 0
(-7425 1550);
DISPLAY 0.680851 (-7425 1550);
DISPLAY INVISIBLE (-7425 1550);
FORCEADD ISL99390FRZTR5935..1
(-6000 1500);
FORCEPROP 1 LAST LOCATION PU23
J 0
(-6300 2375);
DISPLAY 0.489362 (-6300 2375);
PAINT SKYBLUE (-6300 2375);
FORCEPROP 0 LAST $SEC 1
J 0
(-6300 2525);
DISPLAY 0.680851 (-6300 2525);
PAINT MONO (-6300 2525);
DISPLAY INVISIBLE (-6300 2525);
FORCEPROP 2 LAST CDS_SEC 1
J 0
(-6300 2525);
DISPLAY 1.021277 (-6300 2525);
DISPLAY INVISIBLE (-6300 2525);
FORCEPROP 0 LASTPIN (-5600 1050) $PN 2
J 0
(-5590 1060);
DISPLAY 0.489362 (-5590 1060);
PAINT MONO (-5590 1060);
FORCEPROP 0 LASTPIN (-5600 1850) $PN 33
J 0
(-5590 1860);
DISPLAY 0.489362 (-5590 1860);
PAINT MONO (-5590 1860);
FORCEPROP 0 LASTPIN (-6450 1250) $PN 31
J 2
(-6460 1260);
DISPLAY 0.489362 (-6460 1260);
PAINT MONO (-6460 1260);
FORCEPROP 0 LASTPIN (-6450 1650) $PN 35
J 2
(-6460 1660);
DISPLAY 0.489362 (-6460 1660);
PAINT MONO (-6460 1660);
FORCEPROP 0 LASTPIN (-5600 1200) $PN 6
J 0
(-5590 1210);
DISPLAY 0.489362 (-5590 1210);
PAINT MONO (-5590 1210);
FORCEPROP 0 LASTPIN (-5600 1150) $PN 41
J 0
(-5590 1160);
DISPLAY 0.489362 (-5590 1160);
PAINT MONO (-5590 1160);
FORCEPROP 0 LASTPIN (-6450 1500) $PN 38
J 2
(-6460 1510);
DISPLAY 0.489362 (-6460 1510);
PAINT MONO (-6460 1510);
FORCEPROP 0 LASTPIN (-6450 1200) $PN 37
J 2
(-6460 1210);
DISPLAY 0.489362 (-6460 1210);
PAINT MONO (-6460 1210);
FORCEPROP 0 LASTPIN (-5600 1000) $PN 5
J 0
(-5590 1010);
DISPLAY 0.489362 (-5590 1010);
PAINT MONO (-5590 1010);
FORCEPROP 0 LASTPIN (-5600 950) $PN 7_9-20_24
J 0
(-5590 960);
DISPLAY 0.489362 (-5590 960);
PAINT MONO (-5590 960);
FORCEPROP 0 LASTPIN (-5600 900) $PN 40
J 0
(-5590 910);
DISPLAY 0.489362 (-5590 910);
PAINT MONO (-5590 910);
FORCEPROP 0 LASTPIN (-5600 1600) $PN 32
J 0
(-5590 1610);
DISPLAY 0.489362 (-5590 1610);
PAINT MONO (-5590 1610);
FORCEPROP 0 LASTPIN (-6450 2150) $PN 4
J 2
(-6460 2160);
DISPLAY 0.489362 (-6460 2160);
PAINT MONO (-6460 2160);
FORCEPROP 0 LASTPIN (-6450 900) $PN 34
J 2
(-6460 910);
DISPLAY 0.489362 (-6460 910);
PAINT MONO (-6460 910);
FORCEPROP 0 LASTPIN (-6450 1400) $PN 39
J 2
(-6460 1410);
DISPLAY 0.489362 (-6460 1410);
PAINT MONO (-6460 1410);
FORCEPROP 0 LASTPIN (-5600 1500) $PN 10_19
J 0
(-5590 1510);
DISPLAY 0.489362 (-5590 1510);
PAINT MONO (-5590 1510);
FORCEPROP 0 LASTPIN (-6450 1000) $PN 36
J 2
(-6460 1010);
DISPLAY 0.489362 (-6460 1010);
PAINT MONO (-6460 1010);
FORCEPROP 0 LASTPIN (-6450 1850) $PN 3
J 2
(-6460 1860);
DISPLAY 0.489362 (-6460 1860);
PAINT MONO (-6460 1860);
FORCEPROP 0 LASTPIN (-5600 2150) $PN 25_29
J 0
(-5590 2160);
DISPLAY 0.489362 (-5590 2160);
PAINT MONO (-5590 2160);
FORCEPROP 0 LASTPIN (-5600 2100) $PN 30
J 0
(-5590 2110);
DISPLAY 0.489362 (-5590 2110);
PAINT MONO (-5590 2110);
FORCEPROP 0 LASTPIN (-5600 1250) $PN 1
J 0
(-5590 1260);
DISPLAY 0.489362 (-5590 1260);
PAINT MONO (-5590 1260);
FORCEPROP 2 LAST PART_TYPE SMLF
J 0
(-6300 2475);
DISPLAY 1.021277 (-6300 2475);
FORCEPROP 2 LAST VALUE ISL99390FRZ-TR5935
J 0
(-6300 2425);
DISPLAY 0.489362 (-6300 2425);
PAINT SKYBLUE (-6300 2425);
FORCEPROP 1 LAST MATERIAL IC
J 0
(-6300 2225);
DISPLAY 0.489362 (-6300 2225);
PAINT SKYBLUE (-6300 2225);
FORCEPROP 2 LAST CDS_LIB pure_quanta
J 0
(-6000 1500);
DISPLAY INVISIBLE (-6000 1500);
FORCEPROP 1 LAST NEEDS_NO_SIZE TRUE
J 0
(-6000 1500);
DISPLAY 0.723404 (-6000 1500);
PAINT GREEN (-6000 1500);
DISPLAY INVISIBLE (-6000 1500);
FORCEPROP 1 LAST CDS_LMAN_SYM_OUTLINE -300,700,250,-650
J 0
(-6000 1500);
DISPLAY 0.468085 (-6000 1500);
PAINT GREEN (-6000 1500);
DISPLAY INVISIBLE (-6000 1500);
FORCEPROP 1 LAST PATH I13
J 0
(-6000 1500);
DISPLAY 0.723404 (-6000 1500);
PAINT GREEN (-6000 1500);
DISPLAY INVISIBLE (-6000 1500);
FORCEPROP 1 LAST PART_NUMBER AL099390004
J 0
(-6300 2300);
DISPLAY 0.489362 (-6300 2300);
PAINT SKYBLUE (-6300 2300);
DISPLAY INVISIBLE (-6300 2300);
FORCEADD Q_RES..2
(-7775 2375);
FORCEPROP 1 LAST LOCATION PR132
J 0
(-7730 2500);
DISPLAY 0.489362 (-7730 2500);
PAINT SKYBLUE (-7730 2500);
FORCEPROP 0 LAST $SEC 1
J 0
(-7725 2550);
DISPLAY 0.680851 (-7725 2550);
PAINT MONO (-7725 2550);
DISPLAY INVISIBLE (-7725 2550);
FORCEPROP 0 LAST CDS_SEC 1
J 0
(-7725 2550);
DISPLAY 1.021277 (-7725 2550);
DISPLAY INVISIBLE (-7725 2550);
FORCEPROP 1 LASTPIN (-7775 2475) $PN 1
J 0
(-7770 2437);
DISPLAY 0.489362 (-7770 2437);
PAINT MONO (-7770 2437);
FORCEPROP 1 LASTPIN (-7775 2275) $PN 2
J 0
(-7770 2285);
DISPLAY 0.489362 (-7770 2285);
PAINT MONO (-7770 2285);
FORCEPROP 1 LAST TOLERANCE 1%
J 0
(-7725 2400);
DISPLAY 0.489362 (-7725 2400);
PAINT SKYBLUE (-7725 2400);
FORCEPROP 1 LAST WATTAGE 1/16W
J 0
(-7725 2350);
DISPLAY 0.489362 (-7725 2350);
PAINT SKYBLUE (-7725 2350);
FORCEPROP 1 LAST MATERIAL CHIP
J 0
(-7725 2300);
DISPLAY 0.489362 (-7725 2300);
PAINT SKYBLUE (-7725 2300);
FORCEPROP 1 LAST VALUE 2.2
J 0
(-7725 2450);
DISPLAY 0.489362 (-7725 2450);
PAINT SKYBLUE (-7725 2450);
FORCEPROP 1 LAST PACK_TYPE 0402LF
J 0
(-7725 2200);
DISPLAY 0.489362 (-7725 2200);
PAINT SKYBLUE (-7725 2200);
FORCEPROP 2 LAST CDS_LIB pure_quanta
J 0
(-7775 2375);
DISPLAY INVISIBLE (-7775 2375);
FORCEPROP 1 LAST PATH I14
J 0
(-7725 2550);
DISPLAY 0.978723 (-7725 2550);
PAINT WHITE (-7725 2550);
DISPLAY INVISIBLE (-7725 2550);
FORCEPROP 1 LAST PART_NUMBER CS-2202FB01
J 0
(-7725 2250);
DISPLAY 0.489362 (-7725 2250);
PAINT SKYBLUE (-7725 2250);
DISPLAY INVISIBLE (-7725 2250);
FORCEADD VCC_CORE..1
(-7775 2800);
FORCEPROP 3 LASTPIN (-7775 2750) SIG_NAME PVDD11_S3_P0_PVCC\g
J 0
(-7765 2760);
DISPLAY 0.659574 (-7765 2760);
PAINT MONO (-7765 2760);
DISPLAY INVISIBLE (-7765 2760);
FORCEPROP 1 LAST HDL_POWER PVDD11_S3_P0_PVCC
J 1
(-7775 2850);
DISPLAY 0.489362 (-7775 2850);
PAINT GREEN (-7775 2850);
FORCEPROP 2 LAST CDS_LIB pure_quanta_power
J 0
(-7775 2800);
DISPLAY INVISIBLE (-7775 2800);
FORCEPROP 1 LAST PATH I15
J 0
(-7725 2825);
DISPLAY 0.872340 (-7725 2825);
PAINT AQUA (-7725 2825);
DISPLAY INVISIBLE (-7725 2825);
FORCEADD UNIVERSAL_GND..1
(-7425 2125);
FORCEPROP 3 LASTPIN (-7425 2175) SIG_NAME GND\g
J 0
(-7415 2185);
DISPLAY 0.659574 (-7415 2185);
PAINT MONO (-7415 2185);
DISPLAY INVISIBLE (-7415 2185);
FORCEPROP 2 LAST CDS_LIB pure_quanta_power
J 0
(-7425 2125);
DISPLAY INVISIBLE (-7425 2125);
FORCEPROP 1 LAST HDL_POWER GND
J 1
(-7400 2050);
DISPLAY 0.872340 (-7400 2050);
PAINT GREEN (-7400 2050);
DISPLAY INVISIBLE (-7400 2050);
FORCEPROP 1 LAST PATH I16
J 0
(-7350 2125);
DISPLAY 0.872340 (-7350 2125);
PAINT AQUA (-7350 2125);
DISPLAY INVISIBLE (-7350 2125);
FORCEADD Q_CAP..1
(-7425 2400);
FORCEPROP 1 LAST LOCATION PC206_11P0_2
J 0
(-7375 2500);
DISPLAY 0.489362 (-7375 2500);
PAINT SKYBLUE (-7375 2500);
FORCEPROP 0 LAST $SEC 1
J 0
(-7375 2550);
DISPLAY 0.680851 (-7375 2550);
PAINT MONO (-7375 2550);
DISPLAY INVISIBLE (-7375 2550);
FORCEPROP 0 LAST CDS_SEC 1
J 0
(-7375 2550);
DISPLAY 1.021277 (-7375 2550);
DISPLAY INVISIBLE (-7375 2550);
FORCEPROP 1 LASTPIN (-7425 2500) $PN 1
J 0
(-7415 2480);
DISPLAY 0.489362 (-7415 2480);
PAINT MONO (-7415 2480);
FORCEPROP 1 LASTPIN (-7425 2300) $PN 2
J 0
(-7415 2280);
DISPLAY 0.489362 (-7415 2280);
PAINT MONO (-7415 2280);
FORCEPROP 1 LAST PACK_TYPE C0402
J 0
(-7375 2200);
DISPLAY 0.489362 (-7375 2200);
PAINT SKYBLUE (-7375 2200);
FORCEPROP 1 LAST VOLTAGE 10V
J 0
(-7375 2400);
DISPLAY 0.489362 (-7375 2400);
PAINT SKYBLUE (-7375 2400);
FORCEPROP 1 LAST VALUE 2.2UF
J 0
(-7375 2450);
DISPLAY 0.489362 (-7375 2450);
PAINT SKYBLUE (-7375 2450);
FORCEPROP 1 LAST TOLERANCE 10%
J 0
(-7375 2350);
DISPLAY 0.489362 (-7375 2350);
PAINT SKYBLUE (-7375 2350);
FORCEPROP 1 LAST MATERIAL X6S
J 0
(-7375 2300);
DISPLAY 0.489362 (-7375 2300);
PAINT SKYBLUE (-7375 2300);
FORCEPROP 2 LAST CDS_LIB pure_quanta
J 0
(-7425 2400);
DISPLAY INVISIBLE (-7425 2400);
FORCEPROP 1 LAST PATH I17
J 0
(-7375 2550);
DISPLAY 0.978723 (-7375 2550);
PAINT WHITE (-7375 2550);
DISPLAY INVISIBLE (-7375 2550);
FORCEPROP 1 LAST PART_NUMBER CH5222KEB01
J 0
(-7375 2250);
DISPLAY 0.489362 (-7375 2250);
PAINT SKYBLUE (-7375 2250);
DISPLAY INVISIBLE (-7375 2250);
FORCEADD UNIVERSAL_GND..1
(-7875 3875);
FORCEPROP 3 LASTPIN (-7875 3925) SIG_NAME GND\g
J 0
(-7865 3935);
DISPLAY 0.659574 (-7865 3935);
PAINT MONO (-7865 3935);
DISPLAY INVISIBLE (-7865 3935);
FORCEPROP 2 LAST CDS_LIB pure_quanta_power
J 0
(-7875 3875);
DISPLAY INVISIBLE (-7875 3875);
FORCEPROP 1 LAST HDL_POWER GND
J 1
(-7850 3800);
DISPLAY 0.872340 (-7850 3800);
PAINT GREEN (-7850 3800);
DISPLAY INVISIBLE (-7850 3800);
FORCEPROP 1 LAST PATH I18
J 0
(-7800 3875);
DISPLAY 0.872340 (-7800 3875);
PAINT AQUA (-7800 3875);
DISPLAY INVISIBLE (-7800 3875);
FORCEADD UNIVERSAL_GND..1
(-7525 3950);
FORCEPROP 3 LASTPIN (-7525 4000) SIG_NAME GND\g
J 0
(-7515 4010);
DISPLAY 0.659574 (-7515 4010);
PAINT MONO (-7515 4010);
DISPLAY INVISIBLE (-7515 4010);
FORCEPROP 2 LAST CDS_LIB pure_quanta_power
J 0
(-7525 3950);
DISPLAY INVISIBLE (-7525 3950);
FORCEPROP 1 LAST HDL_POWER GND
J 1
(-7500 3875);
DISPLAY 0.872340 (-7500 3875);
PAINT GREEN (-7500 3875);
DISPLAY INVISIBLE (-7500 3875);
FORCEPROP 1 LAST PATH I19
J 0
(-7450 3950);
DISPLAY 0.872340 (-7450 3950);
PAINT AQUA (-7450 3950);
DISPLAY INVISIBLE (-7450 3950);
FORCEADD OFFPAGE..1
(-8100 4325);
FORCEPROP 2 LAST $XR1 208 
J 0
(-8472 4325);
DISPLAY 0.638298 (-8472 4325);
PAINT MONO (-8472 4325);
FORCEPROP 2 LAST $XR0 207 
J 0
(-8352 4325);
DISPLAY 0.638298 (-8352 4325);
PAINT MONO (-8352 4325);
FORCEPROP 2 LAST CDS_LIB standard
J 0
(-8100 4325);
DISPLAY INVISIBLE (-8100 4325);
FORCEPROP 1 LAST OFFPAGE TRUE
J 0
(-7775 4200);
DISPLAY 0.872340 (-7775 4200);
PAINT GREEN (-7775 4200);
DISPLAY INVISIBLE (-7775 4200);
FORCEPROP 1 LAST COMMENT_BODY TRUE
J 0
(-7975 4225);
DISPLAY 0.872340 (-7975 4225);
PAINT GREEN (-7975 4225);
DISPLAY INVISIBLE (-7975 4225);
FORCEPROP 2 LAST PATH I2
J 0
(-8375 4375);
DISPLAY 0.680851 (-8375 4375);
DISPLAY INVISIBLE (-8375 4375);
FORCEADD OFFPAGE..2
R 2
(-7175 3925);
FORCEPROP 2 LAST $XR1 207 
J 0
(-7460 3889);
DISPLAY 0.638298 (-7460 3889);
PAINT MONO (-7460 3889);
FORCEPROP 2 LAST $XR0 208 
J 0
(-7460 3925);
DISPLAY 0.638298 (-7460 3925);
PAINT MONO (-7460 3925);
FORCEPROP 2 LAST CDS_LIB standard
J 0
(-7175 3925);
DISPLAY INVISIBLE (-7175 3925);
FORCEPROP 1 LAST OFFPAGE TRUE
J 2
(-7500 3800);
DISPLAY 0.872340 (-7500 3800);
PAINT GREEN (-7500 3800);
DISPLAY INVISIBLE (-7500 3800);
FORCEPROP 1 LAST COMMENT_BODY TRUE
J 2
(-7130 3830);
DISPLAY 0.872340 (-7130 3830);
PAINT GREEN (-7130 3830);
DISPLAY INVISIBLE (-7130 3830);
FORCEPROP 2 LAST PATH I20
J 0
(-7425 3975);
DISPLAY 0.680851 (-7425 3975);
DISPLAY INVISIBLE (-7425 3975);
FORCEADD OFFPAGE..1
(-7150 3825);
FORCEPROP 2 LAST $XR0 207 
J 0
(-7402 3825);
DISPLAY 0.638298 (-7402 3825);
PAINT MONO (-7402 3825);
FORCEPROP 2 LAST CDS_LIB standard
J 2
(-7150 3825);
DISPLAY INVISIBLE (-7150 3825);
FORCEPROP 1 LAST OFFPAGE TRUE
J 0
(-6825 3700);
DISPLAY 0.872340 (-6825 3700);
PAINT GREEN (-6825 3700);
DISPLAY INVISIBLE (-6825 3700);
FORCEPROP 1 LAST COMMENT_BODY TRUE
J 0
(-7025 3725);
DISPLAY 0.872340 (-7025 3725);
PAINT GREEN (-7025 3725);
DISPLAY INVISIBLE (-7025 3725);
FORCEPROP 2 LAST PATH I21
J 0
(-7400 3875);
DISPLAY 0.680851 (-7400 3875);
DISPLAY INVISIBLE (-7400 3875);
FORCEADD UNIVERSAL_GND..1
(-5425 775);
FORCEPROP 3 LASTPIN (-5425 825) SIG_NAME GND\g
J 0
(-5415 835);
DISPLAY 0.659574 (-5415 835);
PAINT MONO (-5415 835);
DISPLAY INVISIBLE (-5415 835);
FORCEPROP 2 LAST CDS_LIB pure_quanta_power
J 0
(-5425 775);
DISPLAY INVISIBLE (-5425 775);
FORCEPROP 1 LAST HDL_POWER GND
J 1
(-5400 700);
DISPLAY 0.872340 (-5400 700);
PAINT GREEN (-5400 700);
DISPLAY INVISIBLE (-5400 700);
FORCEPROP 1 LAST PATH I22
J 0
(-5350 775);
DISPLAY 0.872340 (-5350 775);
PAINT AQUA (-5350 775);
DISPLAY INVISIBLE (-5350 775);
FORCEADD UNIVERSAL_GND..1
(-4550 600);
FORCEPROP 3 LASTPIN (-4550 650) SIG_NAME GND\g
J 0
(-4540 660);
DISPLAY 0.659574 (-4540 660);
PAINT MONO (-4540 660);
DISPLAY INVISIBLE (-4540 660);
FORCEPROP 2 LAST CDS_LIB pure_quanta_power
J 0
(-4550 600);
DISPLAY INVISIBLE (-4550 600);
FORCEPROP 1 LAST HDL_POWER GND
J 1
(-4525 525);
DISPLAY 0.872340 (-4525 525);
PAINT GREEN (-4525 525);
DISPLAY INVISIBLE (-4525 525);
FORCEPROP 1 LAST PATH I23
J 0
(-4475 600);
DISPLAY 0.872340 (-4475 600);
PAINT AQUA (-4475 600);
DISPLAY INVISIBLE (-4475 600);
FORCEADD Q_RES..2
(-4550 825);
FORCEPROP 1 LAST LOCATION PR389
J 0
(-4505 950);
DISPLAY 0.489362 (-4505 950);
PAINT SKYBLUE (-4505 950);
FORCEPROP 0 LAST $SEC 1
J 0
(-4500 1000);
DISPLAY 0.680851 (-4500 1000);
PAINT MONO (-4500 1000);
DISPLAY INVISIBLE (-4500 1000);
FORCEPROP 0 LAST CDS_SEC 1
J 0
(-4500 1000);
DISPLAY 1.021277 (-4500 1000);
DISPLAY INVISIBLE (-4500 1000);
FORCEPROP 1 LASTPIN (-4550 925) $PN 1
J 0
(-4545 887);
DISPLAY 0.489362 (-4545 887);
PAINT MONO (-4545 887);
FORCEPROP 1 LASTPIN (-4550 725) $PN 2
J 0
(-4545 735);
DISPLAY 0.489362 (-4545 735);
PAINT MONO (-4545 735);
FORCEPROP 1 LAST MATERIAL EMPTY
J 0
(-4510 750);
DISPLAY 0.489362 (-4510 750);
PAINT RED (-4510 750);
FORCEPROP 1 LAST PACK_TYPE 0402LF
J 0
(-4510 650);
DISPLAY 0.489362 (-4510 650);
PAINT SKYBLUE (-4510 650);
FORCEPROP 1 LAST VALUE 1.5
J 0
(-4505 900);
DISPLAY 0.489362 (-4505 900);
PAINT SKYBLUE (-4505 900);
FORCEPROP 1 LAST TOLERANCE 1%
J 0
(-4505 850);
DISPLAY 0.489362 (-4505 850);
PAINT SKYBLUE (-4505 850);
FORCEPROP 1 LAST WATTAGE 1/8W
J 0
(-4510 800);
DISPLAY 0.489362 (-4510 800);
PAINT SKYBLUE (-4510 800);
FORCEPROP 2 LAST CDS_LIB pure_quanta
J 0
(-4550 825);
DISPLAY INVISIBLE (-4550 825);
FORCEPROP 1 LAST PATH I24
J 0
(-4500 1000);
DISPLAY 0.978723 (-4500 1000);
PAINT WHITE (-4500 1000);
DISPLAY INVISIBLE (-4500 1000);
FORCEPROP 1 LAST PART_NUMBER CS-1504FB00
J 0
(-4510 700);
DISPLAY 0.489362 (-4510 700);
PAINT SKYBLUE (-4510 700);
DISPLAY INVISIBLE (-4510 700);
FORCEADD Q_RES..1
(-4675 1850);
FORCEPROP 1 LAST LOCATION PR136
J 0
(-4700 1900);
DISPLAY 0.489362 (-4700 1900);
PAINT SKYBLUE (-4700 1900);
FORCEPROP 0 LAST $SEC 1
J 0
(-4650 1925);
DISPLAY 0.680851 (-4650 1925);
PAINT MONO (-4650 1925);
DISPLAY INVISIBLE (-4650 1925);
FORCEPROP 0 LAST CDS_SEC 1
J 0
(-4650 1925);
DISPLAY 1.021277 (-4650 1925);
DISPLAY INVISIBLE (-4650 1925);
FORCEPROP 1 LASTPIN (-4775 1850) $PN 1
J 0
(-4763 1862);
DISPLAY 0.489362 (-4763 1862);
PAINT MONO (-4763 1862);
FORCEPROP 1 LASTPIN (-4575 1850) $PN 2
J 0
(-4613 1862);
DISPLAY 0.489362 (-4613 1862);
PAINT MONO (-4613 1862);
FORCEPROP 1 LAST VALUE 5.6
J 2
(-4775 1875);
DISPLAY 0.489362 (-4775 1875);
PAINT SKYBLUE (-4775 1875);
FORCEPROP 1 LAST TOLERANCE 1%
J 0
(-4575 1875);
DISPLAY 0.489362 (-4575 1875);
PAINT SKYBLUE (-4575 1875);
FORCEPROP 1 LAST PACK_TYPE 0402LF
J 0
(-4575 1750);
DISPLAY 0.489362 (-4575 1750);
PAINT SKYBLUE (-4575 1750);
FORCEPROP 1 LAST WATTAGE 1/16W
J 0
(-4575 1800);
DISPLAY 0.489362 (-4575 1800);
PAINT SKYBLUE (-4575 1800);
FORCEPROP 1 LAST MATERIAL CHIP
J 0
(-4925 1750);
DISPLAY 0.489362 (-4925 1750);
PAINT SKYBLUE (-4925 1750);
FORCEPROP 2 LAST CDS_LIB pure_quanta
J 0
(-4675 1850);
DISPLAY INVISIBLE (-4675 1850);
FORCEPROP 1 LAST PATH I25
J 0
(-4725 2000);
DISPLAY 0.978723 (-4725 2000);
PAINT WHITE (-4725 2000);
DISPLAY INVISIBLE (-4725 2000);
FORCEPROP 1 LAST PART_NUMBER CS-5602FB01
J 0
(-4925 1800);
DISPLAY 0.489362 (-4925 1800);
PAINT SKYBLUE (-4925 1800);
DISPLAY INVISIBLE (-4925 1800);
FORCEADD Q_CAP..1
(-4550 1300);
FORCEPROP 1 LAST LOCATION PC168
J 0
(-4500 1400);
DISPLAY 0.489362 (-4500 1400);
PAINT SKYBLUE (-4500 1400);
FORCEPROP 0 LAST $SEC 1
J 0
(-4500 1450);
DISPLAY 0.680851 (-4500 1450);
PAINT MONO (-4500 1450);
DISPLAY INVISIBLE (-4500 1450);
FORCEPROP 0 LAST CDS_SEC 1
J 0
(-4500 1450);
DISPLAY 1.021277 (-4500 1450);
DISPLAY INVISIBLE (-4500 1450);
FORCEPROP 1 LASTPIN (-4550 1400) $PN 1
J 0
(-4540 1380);
DISPLAY 0.489362 (-4540 1380);
PAINT MONO (-4540 1380);
FORCEPROP 1 LASTPIN (-4550 1200) $PN 2
J 0
(-4540 1180);
DISPLAY 0.489362 (-4540 1180);
PAINT MONO (-4540 1180);
FORCEPROP 1 LAST VOLTAGE 50V
J 0
(-4500 1300);
DISPLAY 0.489362 (-4500 1300);
PAINT SKYBLUE (-4500 1300);
FORCEPROP 1 LAST TOLERANCE 10%
J 0
(-4500 1250);
DISPLAY 0.489362 (-4500 1250);
PAINT SKYBLUE (-4500 1250);
FORCEPROP 1 LAST MATERIAL EMPTY
J 0
(-4500 1200);
DISPLAY 0.489362 (-4500 1200);
PAINT RED (-4500 1200);
FORCEPROP 1 LAST PACK_TYPE C0402
J 0
(-4500 1100);
DISPLAY 0.489362 (-4500 1100);
PAINT SKYBLUE (-4500 1100);
FORCEPROP 1 LAST VALUE 560PF
J 0
(-4500 1350);
DISPLAY 0.489362 (-4500 1350);
PAINT SKYBLUE (-4500 1350);
FORCEPROP 2 LAST CDS_LIB pure_quanta
J 0
(-4550 1300);
DISPLAY INVISIBLE (-4550 1300);
FORCEPROP 1 LAST PATH I26
J 0
(-4500 1450);
DISPLAY 0.978723 (-4500 1450);
PAINT WHITE (-4500 1450);
DISPLAY INVISIBLE (-4500 1450);
FORCEPROP 1 LAST PART_NUMBER CH1566K1B09
J 0
(-4500 1150);
DISPLAY 0.489362 (-4500 1150);
PAINT SKYBLUE (-4500 1150);
DISPLAY INVISIBLE (-4500 1150);
FORCEADD Q_CAP..1
(-5325 2400);
FORCEPROP 1 LAST LOCATION PC210_2
J 0
(-5275 2500);
DISPLAY 0.489362 (-5275 2500);
PAINT SKYBLUE (-5275 2500);
FORCEPROP 0 LAST $SEC 1
J 0
(-5275 2525);
DISPLAY 0.680851 (-5275 2525);
PAINT MONO (-5275 2525);
DISPLAY INVISIBLE (-5275 2525);
FORCEPROP 0 LAST CDS_SEC 1
J 0
(-5275 2525);
DISPLAY 1.021277 (-5275 2525);
DISPLAY INVISIBLE (-5275 2525);
FORCEPROP 1 LASTPIN (-5325 2500) $PN 1
J 0
(-5315 2480);
DISPLAY 0.489362 (-5315 2480);
PAINT MONO (-5315 2480);
FORCEPROP 1 LASTPIN (-5325 2300) $PN 2
J 0
(-5315 2280);
DISPLAY 0.489362 (-5315 2280);
PAINT MONO (-5315 2280);
FORCEPROP 1 LAST TOLERANCE 10%
J 0
(-5275 2350);
DISPLAY 0.489362 (-5275 2350);
PAINT SKYBLUE (-5275 2350);
FORCEPROP 1 LAST VALUE 1UF
J 0
(-5275 2450);
DISPLAY 0.489362 (-5275 2450);
PAINT SKYBLUE (-5275 2450);
FORCEPROP 1 LAST PACK_TYPE C0402
J 0
(-5275 2200);
DISPLAY 0.489362 (-5275 2200);
PAINT SKYBLUE (-5275 2200);
FORCEPROP 1 LAST VOLTAGE 25V
J 0
(-5275 2400);
DISPLAY 0.489362 (-5275 2400);
PAINT SKYBLUE (-5275 2400);
FORCEPROP 1 LAST MATERIAL X6S
J 0
(-5275 2300);
DISPLAY 0.489362 (-5275 2300);
PAINT SKYBLUE (-5275 2300);
FORCEPROP 2 LAST CDS_LIB pure_quanta
J 0
(-5325 2400);
DISPLAY INVISIBLE (-5325 2400);
FORCEPROP 1 LAST PATH I27
J 0
(-5275 2550);
DISPLAY 0.978723 (-5275 2550);
PAINT WHITE (-5275 2550);
DISPLAY INVISIBLE (-5275 2550);
FORCEPROP 1 LAST PART_NUMBER CH5104KEB02
J 0
(-5275 2250);
DISPLAY 0.489362 (-5275 2250);
PAINT SKYBLUE (-5275 2250);
DISPLAY INVISIBLE (-5275 2250);
FORCEADD UNIVERSAL_GND..1
(-5425 3700);
FORCEPROP 3 LASTPIN (-5425 3750) SIG_NAME GND\g
J 0
(-5415 3760);
DISPLAY 0.659574 (-5415 3760);
PAINT MONO (-5415 3760);
DISPLAY INVISIBLE (-5415 3760);
FORCEPROP 2 LAST CDS_LIB pure_quanta_power
J 0
(-5425 3700);
DISPLAY INVISIBLE (-5425 3700);
FORCEPROP 1 LAST HDL_POWER GND
J 1
(-5400 3625);
DISPLAY 0.872340 (-5400 3625);
PAINT GREEN (-5400 3625);
DISPLAY INVISIBLE (-5400 3625);
FORCEPROP 1 LAST PATH I28
J 0
(-5350 3700);
DISPLAY 0.872340 (-5350 3700);
PAINT AQUA (-5350 3700);
DISPLAY INVISIBLE (-5350 3700);
FORCEADD Q_CAP..1
(-5000 2400);
FORCEPROP 1 LAST LOCATION PC208_2
J 0
(-4950 2500);
DISPLAY 0.489362 (-4950 2500);
PAINT SKYBLUE (-4950 2500);
FORCEPROP 0 LAST $SEC 1
J 0
(-4950 2550);
DISPLAY 0.680851 (-4950 2550);
PAINT MONO (-4950 2550);
DISPLAY INVISIBLE (-4950 2550);
FORCEPROP 0 LAST CDS_SEC 1
J 0
(-4950 2550);
DISPLAY 1.021277 (-4950 2550);
DISPLAY INVISIBLE (-4950 2550);
FORCEPROP 1 LASTPIN (-5000 2500) $PN 1
J 0
(-4990 2480);
DISPLAY 0.489362 (-4990 2480);
PAINT MONO (-4990 2480);
FORCEPROP 1 LASTPIN (-5000 2300) $PN 2
J 0
(-4990 2280);
DISPLAY 0.489362 (-4990 2280);
PAINT MONO (-4990 2280);
FORCEPROP 1 LAST TOLERANCE 10%
J 0
(-4950 2350);
DISPLAY 0.489362 (-4950 2350);
PAINT SKYBLUE (-4950 2350);
FORCEPROP 1 LAST VALUE 0.1UF
J 0
(-4950 2450);
DISPLAY 0.489362 (-4950 2450);
PAINT SKYBLUE (-4950 2450);
FORCEPROP 1 LAST VOLTAGE 25V
J 0
(-4950 2400);
DISPLAY 0.489362 (-4950 2400);
PAINT SKYBLUE (-4950 2400);
FORCEPROP 1 LAST MATERIAL X7R
J 0
(-4950 2300);
DISPLAY 0.489362 (-4950 2300);
PAINT SKYBLUE (-4950 2300);
FORCEPROP 1 LAST PACK_TYPE 0402
J 0
(-4950 2200);
DISPLAY 0.489362 (-4950 2200);
PAINT SKYBLUE (-4950 2200);
FORCEPROP 2 LAST CDS_LIB pure_quanta
J 0
(-5000 2400);
DISPLAY INVISIBLE (-5000 2400);
FORCEPROP 1 LAST PATH I29
J 0
(-4950 2550);
DISPLAY 0.978723 (-4950 2550);
PAINT WHITE (-4950 2550);
DISPLAY INVISIBLE (-4950 2550);
FORCEPROP 1 LAST PART_NUMBER CH4104K1B00
J 0
(-4950 2250);
DISPLAY 0.489362 (-4950 2250);
PAINT SKYBLUE (-4950 2250);
DISPLAY INVISIBLE (-4950 2250);
FORCEADD VCC_CORE..1
(-8425 5900);
FORCEPROP 3 LASTPIN (-8425 5850) SIG_NAME P5V_AUX\g
J 0
(-8415 5860);
DISPLAY 0.659574 (-8415 5860);
PAINT MONO (-8415 5860);
DISPLAY INVISIBLE (-8415 5860);
FORCEPROP 1 LAST HDL_POWER P5V_AUX
J 1
(-8425 5950);
DISPLAY 0.489362 (-8425 5950);
PAINT GREEN (-8425 5950);
FORCEPROP 2 LAST CDS_LIB pure_quanta_power
J 0
(-8425 5900);
DISPLAY INVISIBLE (-8425 5900);
FORCEPROP 1 LAST PATH I3
J 0
(-8375 5925);
DISPLAY 0.872340 (-8375 5925);
PAINT AQUA (-8375 5925);
DISPLAY INVISIBLE (-8375 5925);
FORCEADD Q_CAP..1
(-4675 2400);
FORCEPROP 1 LAST LOCATION PC212_2
J 0
(-4625 2500);
DISPLAY 0.489362 (-4625 2500);
PAINT SKYBLUE (-4625 2500);
FORCEPROP 0 LAST $SEC 1
J 0
(-4625 2525);
DISPLAY 0.680851 (-4625 2525);
PAINT MONO (-4625 2525);
DISPLAY INVISIBLE (-4625 2525);
FORCEPROP 0 LAST CDS_SEC 1
J 0
(-4625 2525);
DISPLAY 1.021277 (-4625 2525);
DISPLAY INVISIBLE (-4625 2525);
FORCEPROP 1 LASTPIN (-4675 2500) $PN 1
J 0
(-4665 2480);
DISPLAY 0.489362 (-4665 2480);
PAINT MONO (-4665 2480);
FORCEPROP 1 LASTPIN (-4675 2300) $PN 2
J 0
(-4665 2280);
DISPLAY 0.489362 (-4665 2280);
PAINT MONO (-4665 2280);
FORCEPROP 1 LAST VOLTAGE 16V
J 0
(-4625 2400);
DISPLAY 0.489362 (-4625 2400);
PAINT SKYBLUE (-4625 2400);
FORCEPROP 1 LAST PACK_TYPE C0805
J 0
(-4625 2200);
DISPLAY 0.489362 (-4625 2200);
PAINT SKYBLUE (-4625 2200);
FORCEPROP 1 LAST VALUE 22UF
J 0
(-4625 2450);
DISPLAY 0.489362 (-4625 2450);
PAINT SKYBLUE (-4625 2450);
FORCEPROP 1 LAST TOLERANCE 20%
J 0
(-4625 2350);
DISPLAY 0.489362 (-4625 2350);
PAINT SKYBLUE (-4625 2350);
FORCEPROP 1 LAST MATERIAL X6S
J 0
(-4625 2300);
DISPLAY 0.489362 (-4625 2300);
PAINT SKYBLUE (-4625 2300);
FORCEPROP 2 LAST CDS_LIB pure_quanta
J 0
(-4675 2400);
DISPLAY INVISIBLE (-4675 2400);
FORCEPROP 1 LAST PATH I30
J 0
(-4625 2550);
DISPLAY 0.978723 (-4625 2550);
PAINT WHITE (-4625 2550);
DISPLAY INVISIBLE (-4625 2550);
FORCEPROP 1 LAST PART_NUMBER CH6223MEA01
J 0
(-4625 2250);
DISPLAY 0.489362 (-4625 2250);
PAINT SKYBLUE (-4625 2250);
DISPLAY INVISIBLE (-4625 2250);
FORCEADD Q_CAP..1
(-4375 2400);
FORCEPROP 1 LAST LOCATION PC214_2
J 0
(-4325 2500);
DISPLAY 0.489362 (-4325 2500);
PAINT SKYBLUE (-4325 2500);
FORCEPROP 0 LAST $SEC 1
J 0
(-4325 2525);
DISPLAY 0.680851 (-4325 2525);
PAINT MONO (-4325 2525);
DISPLAY INVISIBLE (-4325 2525);
FORCEPROP 0 LAST CDS_SEC 1
J 0
(-4325 2525);
DISPLAY 1.021277 (-4325 2525);
DISPLAY INVISIBLE (-4325 2525);
FORCEPROP 1 LASTPIN (-4375 2500) $PN 1
J 0
(-4365 2480);
DISPLAY 0.489362 (-4365 2480);
PAINT MONO (-4365 2480);
FORCEPROP 1 LASTPIN (-4375 2300) $PN 2
J 0
(-4365 2280);
DISPLAY 0.489362 (-4365 2280);
PAINT MONO (-4365 2280);
FORCEPROP 1 LAST MATERIAL X6S
J 0
(-4325 2300);
DISPLAY 0.489362 (-4325 2300);
PAINT SKYBLUE (-4325 2300);
FORCEPROP 1 LAST TOLERANCE 20%
J 0
(-4325 2350);
DISPLAY 0.489362 (-4325 2350);
PAINT SKYBLUE (-4325 2350);
FORCEPROP 1 LAST VOLTAGE 16V
J 0
(-4325 2400);
DISPLAY 0.489362 (-4325 2400);
PAINT SKYBLUE (-4325 2400);
FORCEPROP 1 LAST PACK_TYPE C0805
J 0
(-4325 2200);
DISPLAY 0.489362 (-4325 2200);
PAINT SKYBLUE (-4325 2200);
FORCEPROP 1 LAST VALUE 22UF
J 0
(-4325 2450);
DISPLAY 0.489362 (-4325 2450);
PAINT SKYBLUE (-4325 2450);
FORCEPROP 2 LAST CDS_LIB pure_quanta
J 0
(-4375 2400);
DISPLAY INVISIBLE (-4375 2400);
FORCEPROP 1 LAST PATH I31
J 0
(-4325 2550);
DISPLAY 0.978723 (-4325 2550);
PAINT WHITE (-4325 2550);
DISPLAY INVISIBLE (-4325 2550);
FORCEPROP 1 LAST PART_NUMBER CH6223MEA01
J 0
(-4325 2250);
DISPLAY 0.489362 (-4325 2250);
PAINT SKYBLUE (-4325 2250);
DISPLAY INVISIBLE (-4325 2250);
FORCEADD UNIVERSAL_GND..1
(-4650 3525);
FORCEPROP 3 LASTPIN (-4650 3575) SIG_NAME GND\g
J 0
(-4640 3585);
DISPLAY 0.659574 (-4640 3585);
PAINT MONO (-4640 3585);
DISPLAY INVISIBLE (-4640 3585);
FORCEPROP 2 LAST CDS_LIB pure_quanta_power
J 0
(-4650 3525);
DISPLAY INVISIBLE (-4650 3525);
FORCEPROP 1 LAST HDL_POWER GND
J 1
(-4625 3450);
DISPLAY 0.872340 (-4625 3450);
PAINT GREEN (-4625 3450);
DISPLAY INVISIBLE (-4625 3450);
FORCEPROP 1 LAST PATH I32
J 0
(-4575 3525);
DISPLAY 0.872340 (-4575 3525);
PAINT AQUA (-4575 3525);
DISPLAY INVISIBLE (-4575 3525);
FORCEADD Q_RES..2
(-4650 3750);
FORCEPROP 1 LAST LOCATION PR482
J 0
(-4605 3875);
DISPLAY 0.489362 (-4605 3875);
PAINT SKYBLUE (-4605 3875);
FORCEPROP 0 LAST $SEC 1
J 0
(-4600 3925);
DISPLAY 0.680851 (-4600 3925);
PAINT MONO (-4600 3925);
DISPLAY INVISIBLE (-4600 3925);
FORCEPROP 0 LAST CDS_SEC 1
J 0
(-4600 3925);
DISPLAY 1.021277 (-4600 3925);
DISPLAY INVISIBLE (-4600 3925);
FORCEPROP 1 LASTPIN (-4650 3850) $PN 1
J 0
(-4645 3812);
DISPLAY 0.489362 (-4645 3812);
PAINT MONO (-4645 3812);
FORCEPROP 1 LASTPIN (-4650 3650) $PN 2
J 0
(-4645 3660);
DISPLAY 0.489362 (-4645 3660);
PAINT MONO (-4645 3660);
FORCEPROP 1 LAST PACK_TYPE 0402LF
J 0
(-4610 3575);
DISPLAY 0.489362 (-4610 3575);
PAINT SKYBLUE (-4610 3575);
FORCEPROP 1 LAST WATTAGE 1/8W
J 0
(-4610 3725);
DISPLAY 0.489362 (-4610 3725);
PAINT SKYBLUE (-4610 3725);
FORCEPROP 1 LAST VALUE 1.5
J 0
(-4605 3825);
DISPLAY 0.489362 (-4605 3825);
PAINT SKYBLUE (-4605 3825);
FORCEPROP 1 LAST TOLERANCE 1%
J 0
(-4605 3775);
DISPLAY 0.489362 (-4605 3775);
PAINT SKYBLUE (-4605 3775);
FORCEPROP 1 LAST MATERIAL EMPTY
J 0
(-4610 3675);
DISPLAY 0.489362 (-4610 3675);
PAINT RED (-4610 3675);
FORCEPROP 2 LAST CDS_LIB pure_quanta
J 0
(-4650 3750);
DISPLAY INVISIBLE (-4650 3750);
FORCEPROP 1 LAST PATH I33
J 0
(-4600 3925);
DISPLAY 0.978723 (-4600 3925);
PAINT WHITE (-4600 3925);
DISPLAY INVISIBLE (-4600 3925);
FORCEPROP 1 LAST PART_NUMBER CS-1504FB00
J 0
(-4610 3625);
DISPLAY 0.489362 (-4610 3625);
PAINT SKYBLUE (-4610 3625);
DISPLAY INVISIBLE (-4610 3625);
FORCEADD Q_CAP..1
(-7875 4150);
FORCEPROP 1 LAST LOCATION PC201_1
J 0
(-7825 4250);
DISPLAY 0.489362 (-7825 4250);
PAINT SKYBLUE (-7825 4250);
FORCEPROP 0 LAST $SEC 1
J 0
(-7825 4275);
DISPLAY 0.680851 (-7825 4275);
PAINT MONO (-7825 4275);
DISPLAY INVISIBLE (-7825 4275);
FORCEPROP 0 LAST CDS_SEC 1
J 0
(-7825 4275);
DISPLAY 1.021277 (-7825 4275);
DISPLAY INVISIBLE (-7825 4275);
FORCEPROP 1 LASTPIN (-7875 4250) $PN 1
J 0
(-7865 4230);
DISPLAY 0.489362 (-7865 4230);
PAINT MONO (-7865 4230);
FORCEPROP 1 LASTPIN (-7875 4050) $PN 2
J 0
(-7865 4030);
DISPLAY 0.489362 (-7865 4030);
PAINT MONO (-7865 4030);
FORCEPROP 1 LAST PACK_TYPE 0402
J 0
(-7825 3950);
DISPLAY 0.489362 (-7825 3950);
PAINT SKYBLUE (-7825 3950);
FORCEPROP 1 LAST VOLTAGE 25V
J 0
(-7825 4150);
DISPLAY 0.489362 (-7825 4150);
PAINT SKYBLUE (-7825 4150);
FORCEPROP 1 LAST VALUE 0.1UF
J 0
(-7825 4200);
DISPLAY 0.489362 (-7825 4200);
PAINT SKYBLUE (-7825 4200);
FORCEPROP 1 LAST TOLERANCE 10%
J 0
(-7825 4100);
DISPLAY 0.489362 (-7825 4100);
PAINT SKYBLUE (-7825 4100);
FORCEPROP 1 LAST MATERIAL X7R
J 0
(-7825 4050);
DISPLAY 0.489362 (-7825 4050);
PAINT SKYBLUE (-7825 4050);
FORCEPROP 2 LAST CDS_LIB pure_quanta
J 0
(-7875 4150);
DISPLAY INVISIBLE (-7875 4150);
FORCEPROP 1 LAST PATH I34
J 0
(-7825 4300);
DISPLAY 0.978723 (-7825 4300);
PAINT WHITE (-7825 4300);
DISPLAY INVISIBLE (-7825 4300);
FORCEPROP 1 LAST PART_NUMBER CH4104K1B00
J 0
(-7825 4000);
DISPLAY 0.489362 (-7825 4000);
PAINT SKYBLUE (-7825 4000);
DISPLAY INVISIBLE (-7825 4000);
FORCEADD UNIVERSAL_GND..1
(-7775 4550);
FORCEPROP 3 LASTPIN (-7775 4600) SIG_NAME GND\g
J 0
(-7765 4610);
DISPLAY 0.659574 (-7765 4610);
PAINT MONO (-7765 4610);
DISPLAY INVISIBLE (-7765 4610);
FORCEPROP 2 LAST CDS_LIB pure_quanta_power
J 0
(-7775 4550);
DISPLAY INVISIBLE (-7775 4550);
FORCEPROP 1 LAST HDL_POWER GND
J 1
(-7750 4475);
DISPLAY 0.872340 (-7750 4475);
PAINT GREEN (-7750 4475);
DISPLAY INVISIBLE (-7750 4475);
FORCEPROP 1 LAST PATH I35
J 0
(-7700 4550);
DISPLAY 0.872340 (-7700 4550);
PAINT AQUA (-7700 4550);
DISPLAY INVISIBLE (-7700 4550);
FORCEADD Q_CAP..1
(-7775 4750);
FORCEPROP 1 LAST LOCATION PC203
J 0
(-7725 4850);
DISPLAY 0.489362 (-7725 4850);
PAINT SKYBLUE (-7725 4850);
FORCEPROP 0 LAST $SEC 1
J 0
(-7725 4900);
DISPLAY 0.680851 (-7725 4900);
PAINT MONO (-7725 4900);
DISPLAY INVISIBLE (-7725 4900);
FORCEPROP 0 LAST CDS_SEC 1
J 0
(-7725 4900);
DISPLAY 1.021277 (-7725 4900);
DISPLAY INVISIBLE (-7725 4900);
FORCEPROP 1 LASTPIN (-7775 4850) $PN 1
J 0
(-7765 4830);
DISPLAY 0.489362 (-7765 4830);
PAINT MONO (-7765 4830);
FORCEPROP 1 LASTPIN (-7775 4650) $PN 2
J 0
(-7765 4630);
DISPLAY 0.489362 (-7765 4630);
PAINT MONO (-7765 4630);
FORCEPROP 1 LAST VALUE 2.2UF
J 0
(-7725 4800);
DISPLAY 0.489362 (-7725 4800);
PAINT SKYBLUE (-7725 4800);
FORCEPROP 1 LAST PACK_TYPE C0402
J 0
(-7725 4550);
DISPLAY 0.489362 (-7725 4550);
PAINT SKYBLUE (-7725 4550);
FORCEPROP 1 LAST VOLTAGE 10V
J 0
(-7725 4750);
DISPLAY 0.489362 (-7725 4750);
PAINT SKYBLUE (-7725 4750);
FORCEPROP 1 LAST TOLERANCE 10%
J 0
(-7725 4700);
DISPLAY 0.489362 (-7725 4700);
PAINT SKYBLUE (-7725 4700);
FORCEPROP 1 LAST MATERIAL X6S
J 0
(-7725 4650);
DISPLAY 0.489362 (-7725 4650);
PAINT SKYBLUE (-7725 4650);
FORCEPROP 2 LAST CDS_LIB pure_quanta
J 0
(-7775 4750);
DISPLAY INVISIBLE (-7775 4750);
FORCEPROP 1 LAST PATH I36
J 0
(-7725 4900);
DISPLAY 0.978723 (-7725 4900);
PAINT WHITE (-7725 4900);
DISPLAY INVISIBLE (-7725 4900);
FORCEPROP 1 LAST PART_NUMBER CH5222KEB01
J 0
(-7725 4600);
DISPLAY 0.489362 (-7725 4600);
PAINT SKYBLUE (-7725 4600);
DISPLAY INVISIBLE (-7725 4600);
FORCEADD Q_RES..1
(-7200 4125);
FORCEPROP 1 LAST LOCATION PR133
J 0
(-7200 4175);
DISPLAY 0.489362 (-7200 4175);
PAINT SKYBLUE (-7200 4175);
FORCEPROP 0 LAST $SEC 1
J 0
(-7200 4200);
DISPLAY 0.680851 (-7200 4200);
PAINT MONO (-7200 4200);
DISPLAY INVISIBLE (-7200 4200);
FORCEPROP 0 LAST CDS_SEC 1
J 0
(-7200 4200);
DISPLAY 1.021277 (-7200 4200);
DISPLAY INVISIBLE (-7200 4200);
FORCEPROP 1 LASTPIN (-7300 4125) $PN 1
J 0
(-7288 4137);
DISPLAY 0.489362 (-7288 4137);
PAINT MONO (-7288 4137);
FORCEPROP 1 LASTPIN (-7100 4125) $PN 2
J 0
(-7138 4137);
DISPLAY 0.489362 (-7138 4137);
PAINT MONO (-7138 4137);
FORCEPROP 1 LAST PACK_TYPE 0402LF
J 0
(-7100 4075);
DISPLAY 0.489362 (-7100 4075);
PAINT SKYBLUE (-7100 4075);
FORCEPROP 1 LAST VALUE 4.87K
J 2
(-7275 4150);
DISPLAY 0.489362 (-7275 4150);
PAINT SKYBLUE (-7275 4150);
FORCEPROP 1 LAST TOLERANCE 1%
J 0
(-7075 4150);
DISPLAY 0.489362 (-7075 4150);
PAINT SKYBLUE (-7075 4150);
FORCEPROP 1 LAST MATERIAL EMPTY
J 0
(-7500 4025);
DISPLAY 0.489362 (-7500 4025);
PAINT RED (-7500 4025);
FORCEPROP 1 LAST WATTAGE 1/16W
J 0
(-7100 4025);
DISPLAY 0.489362 (-7100 4025);
PAINT SKYBLUE (-7100 4025);
FORCEPROP 2 LAST CDS_LIB pure_quanta
J 0
(-7200 4125);
DISPLAY INVISIBLE (-7200 4125);
FORCEPROP 1 LAST PATH I37
J 0
(-7250 4275);
DISPLAY 0.978723 (-7250 4275);
PAINT WHITE (-7250 4275);
DISPLAY INVISIBLE (-7250 4275);
FORCEPROP 1 LAST PART_NUMBER CS24872FB01
J 0
(-7500 4075);
DISPLAY 0.489362 (-7500 4075);
PAINT SKYBLUE (-7500 4075);
DISPLAY INVISIBLE (-7500 4075);
FORCEADD OFFPAGE..2
R 2
(-7200 4425);
FORCEPROP 2 LAST $XR0 207 
J 0
(-7455 4425);
DISPLAY 0.638298 (-7455 4425);
PAINT MONO (-7455 4425);
FORCEPROP 2 LAST CDS_LIB standard
J 2
(-7200 4425);
DISPLAY INVISIBLE (-7200 4425);
FORCEPROP 1 LAST OFFPAGE TRUE
J 2
(-7525 4300);
DISPLAY 0.872340 (-7525 4300);
PAINT GREEN (-7525 4300);
DISPLAY INVISIBLE (-7525 4300);
FORCEPROP 1 LAST COMMENT_BODY TRUE
J 2
(-7155 4330);
DISPLAY 0.872340 (-7155 4330);
PAINT GREEN (-7155 4330);
DISPLAY INVISIBLE (-7155 4330);
FORCEPROP 2 LAST PATH I38
J 0
(-7450 4475);
DISPLAY 0.680851 (-7450 4475);
DISPLAY INVISIBLE (-7450 4475);
FORCEADD UNIVERSAL_GND..1
(-7425 5050);
FORCEPROP 3 LASTPIN (-7425 5100) SIG_NAME GND\g
J 0
(-7415 5110);
DISPLAY 0.659574 (-7415 5110);
PAINT MONO (-7415 5110);
DISPLAY INVISIBLE (-7415 5110);
FORCEPROP 2 LAST CDS_LIB pure_quanta_power
J 0
(-7425 5050);
DISPLAY INVISIBLE (-7425 5050);
FORCEPROP 1 LAST HDL_POWER GND
J 1
(-7400 4975);
DISPLAY 0.872340 (-7400 4975);
PAINT GREEN (-7400 4975);
DISPLAY INVISIBLE (-7400 4975);
FORCEPROP 1 LAST PATH I39
J 0
(-7350 5050);
DISPLAY 0.872340 (-7350 5050);
PAINT AQUA (-7350 5050);
DISPLAY INVISIBLE (-7350 5050);
FORCEADD UNIVERSAL_GND..1
(-7825 950);
FORCEPROP 3 LASTPIN (-7825 1000) SIG_NAME GND\g
J 0
(-7815 1010);
DISPLAY 0.659574 (-7815 1010);
PAINT MONO (-7815 1010);
DISPLAY INVISIBLE (-7815 1010);
FORCEPROP 2 LAST CDS_LIB pure_quanta_power
J 0
(-7825 950);
DISPLAY INVISIBLE (-7825 950);
FORCEPROP 1 LAST HDL_POWER GND
J 1
(-7800 875);
DISPLAY 0.872340 (-7800 875);
PAINT GREEN (-7800 875);
DISPLAY INVISIBLE (-7800 875);
FORCEPROP 1 LAST PATH I4
J 0
(-7750 950);
DISPLAY 0.872340 (-7750 950);
PAINT AQUA (-7750 950);
DISPLAY INVISIBLE (-7750 950);
FORCEADD Q_RES..2
(-7775 5300);
FORCEPROP 1 LAST LOCATION PR131
J 0
(-7730 5425);
DISPLAY 0.489362 (-7730 5425);
PAINT SKYBLUE (-7730 5425);
FORCEPROP 0 LAST $SEC 1
J 0
(-7725 5475);
DISPLAY 0.680851 (-7725 5475);
PAINT MONO (-7725 5475);
DISPLAY INVISIBLE (-7725 5475);
FORCEPROP 0 LAST CDS_SEC 1
J 0
(-7725 5475);
DISPLAY 1.021277 (-7725 5475);
DISPLAY INVISIBLE (-7725 5475);
FORCEPROP 1 LASTPIN (-7775 5400) $PN 1
J 0
(-7770 5362);
DISPLAY 0.489362 (-7770 5362);
PAINT MONO (-7770 5362);
FORCEPROP 1 LASTPIN (-7775 5200) $PN 2
J 0
(-7770 5210);
DISPLAY 0.489362 (-7770 5210);
PAINT MONO (-7770 5210);
FORCEPROP 1 LAST WATTAGE 1/16W
J 0
(-7725 5275);
DISPLAY 0.489362 (-7725 5275);
PAINT SKYBLUE (-7725 5275);
FORCEPROP 1 LAST MATERIAL CHIP
J 0
(-7725 5225);
DISPLAY 0.489362 (-7725 5225);
PAINT SKYBLUE (-7725 5225);
FORCEPROP 1 LAST TOLERANCE 1%
J 0
(-7725 5325);
DISPLAY 0.489362 (-7725 5325);
PAINT SKYBLUE (-7725 5325);
FORCEPROP 1 LAST VALUE 2.2
J 0
(-7725 5375);
DISPLAY 0.489362 (-7725 5375);
PAINT SKYBLUE (-7725 5375);
FORCEPROP 1 LAST PACK_TYPE 0402LF
J 0
(-7725 5125);
DISPLAY 0.489362 (-7725 5125);
PAINT SKYBLUE (-7725 5125);
FORCEPROP 2 LAST CDS_LIB pure_quanta
J 0
(-7775 5300);
DISPLAY INVISIBLE (-7775 5300);
FORCEPROP 1 LAST PATH I40
J 0
(-7725 5475);
DISPLAY 0.978723 (-7725 5475);
PAINT WHITE (-7725 5475);
DISPLAY INVISIBLE (-7725 5475);
FORCEPROP 1 LAST PART_NUMBER CS-2202FB01
J 0
(-7725 5175);
DISPLAY 0.489362 (-7725 5175);
PAINT SKYBLUE (-7725 5175);
DISPLAY INVISIBLE (-7725 5175);
FORCEADD VCC_CORE..1
(-8075 5900);
FORCEPROP 3 LASTPIN (-8075 5850) SIG_NAME P3V3_AUX\g
J 0
(-8065 5860);
DISPLAY 0.659574 (-8065 5860);
PAINT MONO (-8065 5860);
DISPLAY INVISIBLE (-8065 5860);
FORCEPROP 1 LAST HDL_POWER P3V3_AUX
J 1
(-8075 5950);
DISPLAY 0.489362 (-8075 5950);
PAINT GREEN (-8075 5950);
FORCEPROP 2 LAST CDS_LIB pure_quanta_power
J 0
(-8075 5900);
DISPLAY INVISIBLE (-8075 5900);
FORCEPROP 1 LAST PATH I41
J 0
(-8025 5925);
DISPLAY 0.872340 (-8025 5925);
PAINT AQUA (-8025 5925);
DISPLAY INVISIBLE (-8025 5925);
FORCEADD Q_CAP..1
(-7425 5325);
FORCEPROP 1 LAST LOCATION PC205_11P0_1
J 0
(-7375 5425);
DISPLAY 0.489362 (-7375 5425);
PAINT SKYBLUE (-7375 5425);
FORCEPROP 0 LAST $SEC 1
J 0
(-7375 5475);
DISPLAY 0.680851 (-7375 5475);
PAINT MONO (-7375 5475);
DISPLAY INVISIBLE (-7375 5475);
FORCEPROP 0 LAST CDS_SEC 1
J 0
(-7375 5475);
DISPLAY 1.021277 (-7375 5475);
DISPLAY INVISIBLE (-7375 5475);
FORCEPROP 1 LASTPIN (-7425 5425) $PN 1
J 0
(-7415 5405);
DISPLAY 0.489362 (-7415 5405);
PAINT MONO (-7415 5405);
FORCEPROP 1 LASTPIN (-7425 5225) $PN 2
J 0
(-7415 5205);
DISPLAY 0.489362 (-7415 5205);
PAINT MONO (-7415 5205);
FORCEPROP 1 LAST PACK_TYPE C0402
J 0
(-7375 5125);
DISPLAY 0.489362 (-7375 5125);
PAINT SKYBLUE (-7375 5125);
FORCEPROP 1 LAST VOLTAGE 10V
J 0
(-7375 5325);
DISPLAY 0.489362 (-7375 5325);
PAINT SKYBLUE (-7375 5325);
FORCEPROP 1 LAST VALUE 2.2UF
J 0
(-7375 5375);
DISPLAY 0.489362 (-7375 5375);
PAINT SKYBLUE (-7375 5375);
FORCEPROP 1 LAST TOLERANCE 10%
J 0
(-7375 5275);
DISPLAY 0.489362 (-7375 5275);
PAINT SKYBLUE (-7375 5275);
FORCEPROP 1 LAST MATERIAL X6S
J 0
(-7375 5225);
DISPLAY 0.489362 (-7375 5225);
PAINT SKYBLUE (-7375 5225);
FORCEPROP 2 LAST CDS_LIB pure_quanta
J 0
(-7425 5325);
DISPLAY INVISIBLE (-7425 5325);
FORCEPROP 1 LAST PATH I42
J 0
(-7375 5475);
DISPLAY 0.978723 (-7375 5475);
PAINT WHITE (-7375 5475);
DISPLAY INVISIBLE (-7375 5475);
FORCEPROP 1 LAST PART_NUMBER CH5222KEB01
J 0
(-7375 5175);
DISPLAY 0.489362 (-7375 5175);
PAINT SKYBLUE (-7375 5175);
DISPLAY INVISIBLE (-7375 5175);
FORCEADD VCC_CORE..1
(-7575 5900);
FORCEPROP 3 LASTPIN (-7575 5850) SIG_NAME PVDD11_S3_P0_PVCC\g
J 0
(-7565 5860);
DISPLAY 0.659574 (-7565 5860);
PAINT MONO (-7565 5860);
DISPLAY INVISIBLE (-7565 5860);
FORCEPROP 1 LAST HDL_POWER PVDD11_S3_P0_PVCC
J 1
(-7575 5950);
DISPLAY 0.489362 (-7575 5950);
PAINT GREEN (-7575 5950);
FORCEPROP 2 LAST CDS_LIB pure_quanta_power
J 0
(-7575 5900);
DISPLAY INVISIBLE (-7575 5900);
FORCEPROP 1 LAST PATH I43
J 0
(-7525 5925);
DISPLAY 0.872340 (-7525 5925);
PAINT AQUA (-7525 5925);
DISPLAY INVISIBLE (-7525 5925);
FORCEADD Q_CAP..1
(-5375 5325);
FORCEPROP 1 LAST LOCATION PC209_1
J 0
(-5325 5425);
DISPLAY 0.489362 (-5325 5425);
PAINT SKYBLUE (-5325 5425);
FORCEPROP 0 LAST $SEC 1
J 0
(-5325 5450);
DISPLAY 0.680851 (-5325 5450);
PAINT MONO (-5325 5450);
DISPLAY INVISIBLE (-5325 5450);
FORCEPROP 0 LAST CDS_SEC 1
J 0
(-5325 5450);
DISPLAY 1.021277 (-5325 5450);
DISPLAY INVISIBLE (-5325 5450);
FORCEPROP 1 LASTPIN (-5375 5425) $PN 1
J 0
(-5365 5405);
DISPLAY 0.489362 (-5365 5405);
PAINT MONO (-5365 5405);
FORCEPROP 1 LASTPIN (-5375 5225) $PN 2
J 0
(-5365 5205);
DISPLAY 0.489362 (-5365 5205);
PAINT MONO (-5365 5205);
FORCEPROP 1 LAST VALUE 1UF
J 0
(-5325 5375);
DISPLAY 0.489362 (-5325 5375);
PAINT SKYBLUE (-5325 5375);
FORCEPROP 1 LAST VOLTAGE 25V
J 0
(-5325 5325);
DISPLAY 0.489362 (-5325 5325);
PAINT SKYBLUE (-5325 5325);
FORCEPROP 1 LAST TOLERANCE 10%
J 0
(-5325 5275);
DISPLAY 0.489362 (-5325 5275);
PAINT SKYBLUE (-5325 5275);
FORCEPROP 1 LAST PACK_TYPE C0402
J 0
(-5325 5125);
DISPLAY 0.489362 (-5325 5125);
PAINT SKYBLUE (-5325 5125);
FORCEPROP 1 LAST MATERIAL X6S
J 0
(-5325 5225);
DISPLAY 0.489362 (-5325 5225);
PAINT SKYBLUE (-5325 5225);
FORCEPROP 2 LAST CDS_LIB pure_quanta
J 0
(-5375 5325);
DISPLAY INVISIBLE (-5375 5325);
FORCEPROP 1 LAST PATH I44
J 0
(-5325 5475);
DISPLAY 0.978723 (-5325 5475);
PAINT WHITE (-5325 5475);
DISPLAY INVISIBLE (-5325 5475);
FORCEPROP 1 LAST PART_NUMBER CH5104KEB02
J 0
(-5325 5175);
DISPLAY 0.489362 (-5325 5175);
PAINT SKYBLUE (-5325 5175);
DISPLAY INVISIBLE (-5325 5175);
FORCEADD Q_CAP..1
(-4650 4225);
FORCEPROP 1 LAST LOCATION PC169
J 0
(-4600 4325);
DISPLAY 0.489362 (-4600 4325);
PAINT SKYBLUE (-4600 4325);
FORCEPROP 0 LAST $SEC 1
J 0
(-4600 4375);
DISPLAY 0.680851 (-4600 4375);
PAINT MONO (-4600 4375);
DISPLAY INVISIBLE (-4600 4375);
FORCEPROP 0 LAST CDS_SEC 1
J 0
(-4600 4375);
DISPLAY 1.021277 (-4600 4375);
DISPLAY INVISIBLE (-4600 4375);
FORCEPROP 1 LASTPIN (-4650 4325) $PN 1
J 0
(-4640 4305);
DISPLAY 0.489362 (-4640 4305);
PAINT MONO (-4640 4305);
FORCEPROP 1 LASTPIN (-4650 4125) $PN 2
J 0
(-4640 4105);
DISPLAY 0.489362 (-4640 4105);
PAINT MONO (-4640 4105);
FORCEPROP 1 LAST PACK_TYPE C0402
J 0
(-4600 4025);
DISPLAY 0.489362 (-4600 4025);
PAINT SKYBLUE (-4600 4025);
FORCEPROP 1 LAST TOLERANCE 10%
J 0
(-4600 4175);
DISPLAY 0.489362 (-4600 4175);
PAINT SKYBLUE (-4600 4175);
FORCEPROP 1 LAST VOLTAGE 50V
J 0
(-4600 4225);
DISPLAY 0.489362 (-4600 4225);
PAINT SKYBLUE (-4600 4225);
FORCEPROP 1 LAST MATERIAL EMPTY
J 0
(-4600 4125);
DISPLAY 0.489362 (-4600 4125);
PAINT RED (-4600 4125);
FORCEPROP 1 LAST VALUE 560PF
J 0
(-4600 4275);
DISPLAY 0.489362 (-4600 4275);
PAINT SKYBLUE (-4600 4275);
FORCEPROP 2 LAST CDS_LIB pure_quanta
J 0
(-4650 4225);
DISPLAY INVISIBLE (-4650 4225);
FORCEPROP 1 LAST PATH I45
J 0
(-4600 4375);
DISPLAY 0.978723 (-4600 4375);
PAINT WHITE (-4600 4375);
DISPLAY INVISIBLE (-4600 4375);
FORCEPROP 1 LAST PART_NUMBER CH1566K1B09
J 0
(-4600 4075);
DISPLAY 0.489362 (-4600 4075);
PAINT SKYBLUE (-4600 4075);
DISPLAY INVISIBLE (-4600 4075);
FORCEADD Q_RES..1
(-4750 4775);
FORCEPROP 1 LAST LOCATION PR135
J 0
(-4800 4850);
DISPLAY 0.489362 (-4800 4850);
PAINT SKYBLUE (-4800 4850);
FORCEPROP 0 LAST $SEC 1
J 0
(-4725 4850);
DISPLAY 0.680851 (-4725 4850);
PAINT MONO (-4725 4850);
DISPLAY INVISIBLE (-4725 4850);
FORCEPROP 0 LAST CDS_SEC 1
J 0
(-4725 4850);
DISPLAY 1.021277 (-4725 4850);
DISPLAY INVISIBLE (-4725 4850);
FORCEPROP 1 LASTPIN (-4850 4775) $PN 1
J 0
(-4838 4787);
DISPLAY 0.489362 (-4838 4787);
PAINT MONO (-4838 4787);
FORCEPROP 1 LASTPIN (-4650 4775) $PN 2
J 0
(-4688 4787);
DISPLAY 0.489362 (-4688 4787);
PAINT MONO (-4688 4787);
FORCEPROP 1 LAST MATERIAL CHIP
J 0
(-5000 4675);
DISPLAY 0.489362 (-5000 4675);
PAINT SKYBLUE (-5000 4675);
FORCEPROP 1 LAST PACK_TYPE 0402LF
J 0
(-4650 4675);
DISPLAY 0.489362 (-4650 4675);
PAINT SKYBLUE (-4650 4675);
FORCEPROP 1 LAST TOLERANCE 1%
J 0
(-4650 4800);
DISPLAY 0.489362 (-4650 4800);
PAINT SKYBLUE (-4650 4800);
FORCEPROP 1 LAST WATTAGE 1/16W
J 0
(-4650 4725);
DISPLAY 0.489362 (-4650 4725);
PAINT SKYBLUE (-4650 4725);
FORCEPROP 1 LAST VALUE 5.6
J 2
(-4850 4800);
DISPLAY 0.489362 (-4850 4800);
PAINT SKYBLUE (-4850 4800);
FORCEPROP 2 LAST CDS_LIB pure_quanta
J 0
(-4750 4775);
DISPLAY INVISIBLE (-4750 4775);
FORCEPROP 1 LAST PATH I46
J 0
(-4800 4925);
DISPLAY 0.978723 (-4800 4925);
PAINT WHITE (-4800 4925);
DISPLAY INVISIBLE (-4800 4925);
FORCEPROP 1 LAST PART_NUMBER CS-5602FB01
J 0
(-5000 4725);
DISPLAY 0.489362 (-5000 4725);
PAINT SKYBLUE (-5000 4725);
DISPLAY INVISIBLE (-5000 4725);
FORCEADD Q_CAP..1
(-5050 5325);
FORCEPROP 1 LAST LOCATION PC207_1
J 0
(-5000 5425);
DISPLAY 0.489362 (-5000 5425);
PAINT SKYBLUE (-5000 5425);
FORCEPROP 0 LAST $SEC 1
J 0
(-5000 5475);
DISPLAY 0.680851 (-5000 5475);
PAINT MONO (-5000 5475);
DISPLAY INVISIBLE (-5000 5475);
FORCEPROP 0 LAST CDS_SEC 1
J 0
(-5000 5475);
DISPLAY 1.021277 (-5000 5475);
DISPLAY INVISIBLE (-5000 5475);
FORCEPROP 1 LASTPIN (-5050 5425) $PN 1
J 0
(-5040 5405);
DISPLAY 0.489362 (-5040 5405);
PAINT MONO (-5040 5405);
FORCEPROP 1 LASTPIN (-5050 5225) $PN 2
J 0
(-5040 5205);
DISPLAY 0.489362 (-5040 5205);
PAINT MONO (-5040 5205);
FORCEPROP 1 LAST VOLTAGE 25V
J 0
(-5000 5325);
DISPLAY 0.489362 (-5000 5325);
PAINT SKYBLUE (-5000 5325);
FORCEPROP 1 LAST TOLERANCE 10%
J 0
(-5000 5275);
DISPLAY 0.489362 (-5000 5275);
PAINT SKYBLUE (-5000 5275);
FORCEPROP 1 LAST MATERIAL X7R
J 0
(-5000 5225);
DISPLAY 0.489362 (-5000 5225);
PAINT SKYBLUE (-5000 5225);
FORCEPROP 1 LAST VALUE 0.1UF
J 0
(-5000 5375);
DISPLAY 0.489362 (-5000 5375);
PAINT SKYBLUE (-5000 5375);
FORCEPROP 1 LAST PACK_TYPE 0402
J 0
(-5000 5125);
DISPLAY 0.489362 (-5000 5125);
PAINT SKYBLUE (-5000 5125);
FORCEPROP 2 LAST CDS_LIB pure_quanta
J 0
(-5050 5325);
DISPLAY INVISIBLE (-5050 5325);
FORCEPROP 1 LAST PATH I47
J 0
(-5000 5475);
DISPLAY 0.978723 (-5000 5475);
PAINT WHITE (-5000 5475);
DISPLAY INVISIBLE (-5000 5475);
FORCEPROP 1 LAST PART_NUMBER CH4104K1B00
J 0
(-5000 5175);
DISPLAY 0.489362 (-5000 5175);
PAINT SKYBLUE (-5000 5175);
DISPLAY INVISIBLE (-5000 5175);
FORCEADD Q_CAP..1
(-4750 5325);
FORCEPROP 1 LAST LOCATION PC211_1
J 0
(-4700 5425);
DISPLAY 0.489362 (-4700 5425);
PAINT SKYBLUE (-4700 5425);
FORCEPROP 0 LAST $SEC 1
J 0
(-4700 5450);
DISPLAY 0.680851 (-4700 5450);
PAINT MONO (-4700 5450);
DISPLAY INVISIBLE (-4700 5450);
FORCEPROP 0 LAST CDS_SEC 1
J 0
(-4700 5450);
DISPLAY 1.021277 (-4700 5450);
DISPLAY INVISIBLE (-4700 5450);
FORCEPROP 1 LASTPIN (-4750 5425) $PN 1
J 0
(-4740 5405);
DISPLAY 0.489362 (-4740 5405);
PAINT MONO (-4740 5405);
FORCEPROP 1 LASTPIN (-4750 5225) $PN 2
J 0
(-4740 5205);
DISPLAY 0.489362 (-4740 5205);
PAINT MONO (-4740 5205);
FORCEPROP 1 LAST VOLTAGE 16V
J 0
(-4700 5325);
DISPLAY 0.489362 (-4700 5325);
PAINT SKYBLUE (-4700 5325);
FORCEPROP 1 LAST PACK_TYPE C0805
J 0
(-4700 5125);
DISPLAY 0.489362 (-4700 5125);
PAINT SKYBLUE (-4700 5125);
FORCEPROP 1 LAST MATERIAL X6S
J 0
(-4700 5225);
DISPLAY 0.489362 (-4700 5225);
PAINT SKYBLUE (-4700 5225);
FORCEPROP 1 LAST VALUE 22UF
J 0
(-4700 5375);
DISPLAY 0.489362 (-4700 5375);
PAINT SKYBLUE (-4700 5375);
FORCEPROP 1 LAST TOLERANCE 20%
J 0
(-4700 5275);
DISPLAY 0.489362 (-4700 5275);
PAINT SKYBLUE (-4700 5275);
FORCEPROP 2 LAST CDS_LIB pure_quanta
J 0
(-4750 5325);
DISPLAY INVISIBLE (-4750 5325);
FORCEPROP 1 LAST PATH I48
J 0
(-4700 5475);
DISPLAY 0.978723 (-4700 5475);
PAINT WHITE (-4700 5475);
DISPLAY INVISIBLE (-4700 5475);
FORCEPROP 1 LAST PART_NUMBER CH6223MEA01
J 0
(-4700 5175);
DISPLAY 0.489362 (-4700 5175);
PAINT SKYBLUE (-4700 5175);
DISPLAY INVISIBLE (-4700 5175);
FORCEADD Q_CAP..1
(-4425 5325);
FORCEPROP 1 LAST LOCATION PC213_1
J 0
(-4375 5425);
DISPLAY 0.489362 (-4375 5425);
PAINT SKYBLUE (-4375 5425);
FORCEPROP 0 LAST $SEC 1
J 0
(-4375 5450);
DISPLAY 0.680851 (-4375 5450);
PAINT MONO (-4375 5450);
DISPLAY INVISIBLE (-4375 5450);
FORCEPROP 0 LAST CDS_SEC 1
J 0
(-4375 5450);
DISPLAY 1.021277 (-4375 5450);
DISPLAY INVISIBLE (-4375 5450);
FORCEPROP 1 LASTPIN (-4425 5425) $PN 1
J 0
(-4415 5405);
DISPLAY 0.489362 (-4415 5405);
PAINT MONO (-4415 5405);
FORCEPROP 1 LASTPIN (-4425 5225) $PN 2
J 0
(-4415 5205);
DISPLAY 0.489362 (-4415 5205);
PAINT MONO (-4415 5205);
FORCEPROP 1 LAST VOLTAGE 16V
J 0
(-4375 5325);
DISPLAY 0.489362 (-4375 5325);
PAINT SKYBLUE (-4375 5325);
FORCEPROP 1 LAST VALUE 22UF
J 0
(-4375 5375);
DISPLAY 0.489362 (-4375 5375);
PAINT SKYBLUE (-4375 5375);
FORCEPROP 1 LAST PACK_TYPE C0805
J 0
(-4375 5125);
DISPLAY 0.489362 (-4375 5125);
PAINT SKYBLUE (-4375 5125);
FORCEPROP 1 LAST TOLERANCE 20%
J 0
(-4375 5275);
DISPLAY 0.489362 (-4375 5275);
PAINT SKYBLUE (-4375 5275);
FORCEPROP 1 LAST MATERIAL X6S
J 0
(-4375 5225);
DISPLAY 0.489362 (-4375 5225);
PAINT SKYBLUE (-4375 5225);
FORCEPROP 2 LAST CDS_LIB pure_quanta
J 0
(-4425 5325);
DISPLAY INVISIBLE (-4425 5325);
FORCEPROP 1 LAST PATH I49
J 0
(-4375 5475);
DISPLAY 0.978723 (-4375 5475);
PAINT WHITE (-4375 5475);
DISPLAY INVISIBLE (-4375 5475);
FORCEPROP 1 LAST PART_NUMBER CH6223MEA01
J 0
(-4375 5175);
DISPLAY 0.489362 (-4375 5175);
PAINT SKYBLUE (-4375 5175);
DISPLAY INVISIBLE (-4375 5175);
FORCEADD OFFPAGE..1
(-7100 900);
FORCEPROP 2 LAST $XR0 207 
J 0
(-7352 900);
DISPLAY 0.638298 (-7352 900);
PAINT MONO (-7352 900);
FORCEPROP 2 LAST CDS_LIB standard
J 2
(-7100 900);
DISPLAY INVISIBLE (-7100 900);
FORCEPROP 1 LAST OFFPAGE TRUE
J 0
(-6775 775);
DISPLAY 0.872340 (-6775 775);
PAINT GREEN (-6775 775);
DISPLAY INVISIBLE (-6775 775);
FORCEPROP 1 LAST COMMENT_BODY TRUE
J 0
(-6975 800);
DISPLAY 0.872340 (-6975 800);
PAINT GREEN (-6975 800);
DISPLAY INVISIBLE (-6975 800);
FORCEPROP 2 LAST PATH I5
J 0
(-7375 950);
DISPLAY 0.680851 (-7375 950);
DISPLAY INVISIBLE (-7375 950);
FORCEADD Q_CAP..1
(-4050 2400);
FORCEPROP 1 LAST LOCATION PC216_2
J 0
(-4000 2500);
DISPLAY 0.489362 (-4000 2500);
PAINT SKYBLUE (-4000 2500);
FORCEPROP 0 LAST $SEC 1
J 0
(-4000 2525);
DISPLAY 0.680851 (-4000 2525);
PAINT MONO (-4000 2525);
DISPLAY INVISIBLE (-4000 2525);
FORCEPROP 0 LAST CDS_SEC 1
J 0
(-4000 2525);
DISPLAY 1.021277 (-4000 2525);
DISPLAY INVISIBLE (-4000 2525);
FORCEPROP 1 LASTPIN (-4050 2500) $PN 1
J 0
(-4040 2480);
DISPLAY 0.489362 (-4040 2480);
PAINT MONO (-4040 2480);
FORCEPROP 1 LASTPIN (-4050 2300) $PN 2
J 0
(-4040 2280);
DISPLAY 0.489362 (-4040 2280);
PAINT MONO (-4040 2280);
FORCEPROP 1 LAST MATERIAL X6S
J 0
(-4000 2300);
DISPLAY 0.489362 (-4000 2300);
PAINT SKYBLUE (-4000 2300);
FORCEPROP 1 LAST VOLTAGE 16V
J 0
(-4000 2400);
DISPLAY 0.489362 (-4000 2400);
PAINT SKYBLUE (-4000 2400);
FORCEPROP 1 LAST VALUE 22UF
J 0
(-4000 2450);
DISPLAY 0.489362 (-4000 2450);
PAINT SKYBLUE (-4000 2450);
FORCEPROP 1 LAST TOLERANCE 20%
J 0
(-4000 2350);
DISPLAY 0.489362 (-4000 2350);
PAINT SKYBLUE (-4000 2350);
FORCEPROP 1 LAST PACK_TYPE C0805
J 0
(-4000 2200);
DISPLAY 0.489362 (-4000 2200);
PAINT SKYBLUE (-4000 2200);
FORCEPROP 2 LAST CDS_LIB pure_quanta
J 0
(-4050 2400);
DISPLAY INVISIBLE (-4050 2400);
FORCEPROP 1 LAST PATH I50
J 0
(-4000 2550);
DISPLAY 0.978723 (-4000 2550);
PAINT WHITE (-4000 2550);
DISPLAY INVISIBLE (-4000 2550);
FORCEPROP 1 LAST PART_NUMBER CH6223MEA01
J 0
(-4000 2250);
DISPLAY 0.489362 (-4000 2250);
PAINT SKYBLUE (-4000 2250);
DISPLAY INVISIBLE (-4000 2250);
FORCEADD Q_CAP..1
(-3850 1725);
FORCEPROP 1 LAST LOCATION PC218
J 0
(-3800 1850);
DISPLAY 0.489362 (-3800 1850);
PAINT SKYBLUE (-3800 1850);
FORCEPROP 0 LAST $SEC 1
J 0
(-3800 1875);
DISPLAY 0.680851 (-3800 1875);
PAINT MONO (-3800 1875);
DISPLAY INVISIBLE (-3800 1875);
FORCEPROP 0 LAST CDS_SEC 1
J 0
(-3800 1875);
DISPLAY 1.021277 (-3800 1875);
DISPLAY INVISIBLE (-3800 1875);
FORCEPROP 1 LASTPIN (-3850 1825) $PN 1
J 0
(-3840 1805);
DISPLAY 0.489362 (-3840 1805);
PAINT MONO (-3840 1805);
FORCEPROP 1 LASTPIN (-3850 1625) $PN 2
J 0
(-3840 1605);
DISPLAY 0.489362 (-3840 1605);
PAINT MONO (-3840 1605);
FORCEPROP 1 LAST PACK_TYPE 0402
J 0
(-3800 1550);
DISPLAY 0.489362 (-3800 1550);
PAINT SKYBLUE (-3800 1550);
FORCEPROP 1 LAST VOLTAGE 16V
J 0
(-3800 1750);
DISPLAY 0.489362 (-3800 1750);
PAINT SKYBLUE (-3800 1750);
FORCEPROP 1 LAST VALUE 0.22UF
J 0
(-3800 1800);
DISPLAY 0.489362 (-3800 1800);
PAINT SKYBLUE (-3800 1800);
FORCEPROP 1 LAST TOLERANCE 10%
J 0
(-3800 1700);
DISPLAY 0.489362 (-3800 1700);
PAINT SKYBLUE (-3800 1700);
FORCEPROP 1 LAST MATERIAL X7R
J 0
(-3800 1650);
DISPLAY 0.489362 (-3800 1650);
PAINT SKYBLUE (-3800 1650);
FORCEPROP 2 LAST CDS_LIB pure_quanta
J 0
(-3850 1725);
DISPLAY INVISIBLE (-3850 1725);
FORCEPROP 1 LAST PATH I51
J 0
(-3800 1875);
DISPLAY 0.978723 (-3800 1875);
PAINT WHITE (-3800 1875);
DISPLAY INVISIBLE (-3800 1875);
FORCEPROP 1 LAST PART_NUMBER CH4223K1B00
J 0
(-3800 1600);
DISPLAY 0.489362 (-3800 1600);
PAINT SKYBLUE (-3800 1600);
DISPLAY INVISIBLE (-3800 1600);
FORCEADD Q_INDUCTOR..1
(-3375 1525);
FORCEPROP 1 LAST LOCATION PL22
J 0
(-3400 1575);
DISPLAY 0.489362 (-3400 1575);
PAINT SKYBLUE (-3400 1575);
FORCEPROP 0 LAST $SEC 1
J 0
(-3400 1600);
DISPLAY 0.680851 (-3400 1600);
PAINT MONO (-3400 1600);
DISPLAY INVISIBLE (-3400 1600);
FORCEPROP 0 LAST CDS_SEC 1
J 0
(-3400 1600);
DISPLAY 1.021277 (-3400 1600);
DISPLAY INVISIBLE (-3400 1600);
FORCEPROP 0 LASTPIN (-3475 1500) $PN 1
J 2
(-3485 1510);
DISPLAY 0.489362 (-3485 1510);
PAINT MONO (-3485 1510);
FORCEPROP 0 LASTPIN (-3275 1500) $PN 2
J 0
(-3265 1510);
DISPLAY 0.489362 (-3265 1510);
PAINT MONO (-3265 1510);
FORCEPROP 1 LAST MATERIAL IND
J 0
(-3475 1350);
DISPLAY 0.489362 (-3475 1350);
PAINT SKYBLUE (-3475 1350);
FORCEPROP 2 LAST PACK_TYPE SMLF
J 0
(-3475 1300);
DISPLAY 0.489362 (-3475 1300);
PAINT SKYBLUE (-3475 1300);
FORCEPROP 2 LAST VALUE 90NH/155A
J 0
(-3475 1450);
DISPLAY 0.489362 (-3475 1450);
PAINT SKYBLUE (-3475 1450);
FORCEPROP 1 LAST NEEDS_NO_SIZE TRUE
J 0
(-3375 1525);
DISPLAY 0.468085 (-3375 1525);
PAINT GREEN (-3375 1525);
DISPLAY INVISIBLE (-3375 1525);
FORCEPROP 2 LAST CDS_LIB pure_quanta
J 0
(-3375 1525);
DISPLAY INVISIBLE (-3375 1525);
FORCEPROP 1 LAST PATH I52
J 0
(-3300 1580);
DISPLAY 0.723404 (-3300 1580);
PAINT GREEN (-3300 1580);
DISPLAY INVISIBLE (-3300 1580);
FORCEPROP 1 LAST PART_NUMBER CVA90^0KZ13
J 0
(-3475 1400);
DISPLAY 0.489362 (-3475 1400);
PAINT SKYBLUE (-3475 1400);
DISPLAY INVISIBLE (-3475 1400);
FORCEADD UNIVERSAL_GND..1
(-3700 2075);
FORCEPROP 3 LASTPIN (-3700 2125) SIG_NAME GND\g
J 0
(-3690 2135);
DISPLAY 0.659574 (-3690 2135);
PAINT MONO (-3690 2135);
DISPLAY INVISIBLE (-3690 2135);
FORCEPROP 2 LAST CDS_LIB pure_quanta_power
J 0
(-3700 2075);
DISPLAY INVISIBLE (-3700 2075);
FORCEPROP 1 LAST HDL_POWER GND
J 1
(-3675 2000);
DISPLAY 0.872340 (-3675 2000);
PAINT GREEN (-3675 2000);
DISPLAY INVISIBLE (-3675 2000);
FORCEPROP 1 LAST PATH I53
J 0
(-3625 2075);
DISPLAY 0.872340 (-3625 2075);
PAINT AQUA (-3625 2075);
DISPLAY INVISIBLE (-3625 2075);
FORCEADD Q_CAP..1
(-3700 2400);
FORCEPROP 1 LAST LOCATION PC218_2
J 0
(-3650 2500);
DISPLAY 0.489362 (-3650 2500);
PAINT SKYBLUE (-3650 2500);
FORCEPROP 0 LAST $SEC 1
J 0
(-3650 2525);
DISPLAY 0.680851 (-3650 2525);
PAINT MONO (-3650 2525);
DISPLAY INVISIBLE (-3650 2525);
FORCEPROP 0 LAST CDS_SEC 1
J 0
(-3650 2525);
DISPLAY 1.021277 (-3650 2525);
DISPLAY INVISIBLE (-3650 2525);
FORCEPROP 1 LASTPIN (-3700 2500) $PN 1
J 0
(-3690 2480);
DISPLAY 0.489362 (-3690 2480);
PAINT MONO (-3690 2480);
FORCEPROP 1 LASTPIN (-3700 2300) $PN 2
J 0
(-3690 2280);
DISPLAY 0.489362 (-3690 2280);
PAINT MONO (-3690 2280);
FORCEPROP 1 LAST MATERIAL X6S
J 0
(-3650 2300);
DISPLAY 0.489362 (-3650 2300);
PAINT SKYBLUE (-3650 2300);
FORCEPROP 1 LAST VALUE 22UF
J 0
(-3650 2450);
DISPLAY 0.489362 (-3650 2450);
PAINT SKYBLUE (-3650 2450);
FORCEPROP 1 LAST PACK_TYPE C0805
J 0
(-3650 2200);
DISPLAY 0.489362 (-3650 2200);
PAINT SKYBLUE (-3650 2200);
FORCEPROP 1 LAST TOLERANCE 20%
J 0
(-3650 2350);
DISPLAY 0.489362 (-3650 2350);
PAINT SKYBLUE (-3650 2350);
FORCEPROP 1 LAST VOLTAGE 16V
J 0
(-3650 2400);
DISPLAY 0.489362 (-3650 2400);
PAINT SKYBLUE (-3650 2400);
FORCEPROP 2 LAST CDS_LIB pure_quanta
J 0
(-3700 2400);
DISPLAY INVISIBLE (-3700 2400);
FORCEPROP 1 LAST PATH I54
J 0
(-3650 2550);
DISPLAY 0.978723 (-3650 2550);
PAINT WHITE (-3650 2550);
DISPLAY INVISIBLE (-3650 2550);
FORCEPROP 1 LAST PART_NUMBER CH6223MEA01
J 0
(-3650 2250);
DISPLAY 0.489362 (-3650 2250);
PAINT SKYBLUE (-3650 2250);
DISPLAY INVISIBLE (-3650 2250);
FORCEADD VCC_CORE..1
(-3700 2675);
FORCEPROP 3 LASTPIN (-3700 2625) SIG_NAME SW_P12V_AUX_PVDD11_S3_P0_FLT\g
J 0
(-3690 2635);
DISPLAY 0.659574 (-3690 2635);
PAINT MONO (-3690 2635);
DISPLAY INVISIBLE (-3690 2635);
FORCEPROP 1 LAST HDL_POWER SW_P12V_AUX_PVDD11_S3_P0_FLT
J 1
(-3700 2725);
DISPLAY 0.489362 (-3700 2725);
PAINT GREEN (-3700 2725);
FORCEPROP 2 LAST CDS_LIB pure_quanta_power
J 0
(-3700 2675);
DISPLAY INVISIBLE (-3700 2675);
FORCEPROP 1 LAST PATH I55
J 0
(-3650 2700);
DISPLAY 0.872340 (-3650 2700);
PAINT AQUA (-3650 2700);
DISPLAY INVISIBLE (-3650 2700);
FORCEADD Q_RES..1
(-3775 3450);
FORCEPROP 1 LAST LOCATION PR137
J 0
(-3825 3500);
DISPLAY 0.489362 (-3825 3500);
PAINT SKYBLUE (-3825 3500);
FORCEPROP 0 LAST $SEC 1
J 0
(-3825 3550);
DISPLAY 0.680851 (-3825 3550);
PAINT MONO (-3825 3550);
DISPLAY INVISIBLE (-3825 3550);
FORCEPROP 0 LAST CDS_SEC 1
J 0
(-3825 3550);
DISPLAY 1.021277 (-3825 3550);
DISPLAY INVISIBLE (-3825 3550);
FORCEPROP 1 LASTPIN (-3875 3450) $PN 1
J 0
(-3863 3462);
DISPLAY 0.489362 (-3863 3462);
PAINT MONO (-3863 3462);
FORCEPROP 1 LASTPIN (-3675 3450) $PN 2
J 0
(-3713 3462);
DISPLAY 0.489362 (-3713 3462);
PAINT MONO (-3713 3462);
FORCEPROP 1 LAST PACK_TYPE 0402LF
J 0
(-3675 3375);
DISPLAY 0.489362 (-3675 3375);
PAINT SKYBLUE (-3675 3375);
FORCEPROP 1 LAST TOLERANCE 5%
J 0
(-3650 3475);
DISPLAY 0.489362 (-3650 3475);
PAINT SKYBLUE (-3650 3475);
FORCEPROP 1 LAST WATTAGE 1/16W
J 0
(-3675 3400);
DISPLAY 0.489362 (-3675 3400);
PAINT SKYBLUE (-3675 3400);
FORCEPROP 1 LAST MATERIAL CHIP
J 0
(-4025 3375);
DISPLAY 0.489362 (-4025 3375);
PAINT SKYBLUE (-4025 3375);
FORCEPROP 1 LAST VALUE 0
J 2
(-3900 3475);
DISPLAY 0.489362 (-3900 3475);
PAINT SKYBLUE (-3900 3475);
FORCEPROP 2 LAST CDS_LIB pure_quanta
J 0
(-3775 3450);
DISPLAY INVISIBLE (-3775 3450);
FORCEPROP 1 LAST PATH I56
J 0
(-3825 3600);
DISPLAY 0.978723 (-3825 3600);
PAINT WHITE (-3825 3600);
DISPLAY INVISIBLE (-3825 3600);
FORCEPROP 1 LAST PART_NUMBER CS00002JB13
J 0
(-4025 3400);
DISPLAY 0.489362 (-4025 3400);
PAINT SKYBLUE (-4025 3400);
DISPLAY INVISIBLE (-4025 3400);
FORCEADD UNIVERSAL_GND..1
(-2725 2525);
FORCEPROP 3 LASTPIN (-2725 2575) SIG_NAME GND\g
J 0
(-2715 2585);
DISPLAY 0.659574 (-2715 2585);
PAINT MONO (-2715 2585);
DISPLAY INVISIBLE (-2715 2585);
FORCEPROP 2 LAST CDS_LIB pure_quanta_power
J 0
(-2725 2525);
DISPLAY INVISIBLE (-2725 2525);
FORCEPROP 1 LAST HDL_POWER GND
J 1
(-2700 2450);
DISPLAY 0.872340 (-2700 2450);
PAINT GREEN (-2700 2450);
DISPLAY INVISIBLE (-2700 2450);
FORCEPROP 1 LAST PATH I57
J 0
(-2650 2525);
DISPLAY 0.872340 (-2650 2525);
PAINT AQUA (-2650 2525);
DISPLAY INVISIBLE (-2650 2525);
FORCEADD Q_CAPP..1
(-2725 2850);
FORCEPROP 1 LAST LOCATION PC223
J 0
(-2675 2950);
DISPLAY 0.489362 (-2675 2950);
PAINT SKYBLUE (-2675 2950);
FORCEPROP 0 LAST $SEC 1
J 0
(-2675 2975);
DISPLAY 0.680851 (-2675 2975);
PAINT MONO (-2675 2975);
DISPLAY INVISIBLE (-2675 2975);
FORCEPROP 0 LAST CDS_SEC 1
J 0
(-2675 2975);
DISPLAY 1.021277 (-2675 2975);
DISPLAY INVISIBLE (-2675 2975);
FORCEPROP 1 LASTPIN (-2725 2950) $PN 1
J 0
(-2715 2935);
DISPLAY 0.489362 (-2715 2935);
PAINT MONO (-2715 2935);
FORCEPROP 1 LASTPIN (-2725 2750) $PN 2
J 0
(-2715 2735);
DISPLAY 0.489362 (-2715 2735);
PAINT MONO (-2715 2735);
FORCEPROP 1 LAST VALUE 470UF
J 0
(-2675 2900);
DISPLAY 0.489362 (-2675 2900);
PAINT SKYBLUE (-2675 2900);
FORCEPROP 1 LAST PACK_TYPE SMLF
J 0
(-2675 2700);
DISPLAY 0.489362 (-2675 2700);
PAINT SKYBLUE (-2675 2700);
FORCEPROP 1 LAST VOLTAGE 2.5V
J 0
(-2675 2800);
DISPLAY 0.489362 (-2675 2800);
PAINT SKYBLUE (-2675 2800);
FORCEPROP 1 LAST TOLERANCE 20%
J 0
(-2675 2850);
DISPLAY 0.489362 (-2675 2850);
PAINT SKYBLUE (-2675 2850);
FORCEPROP 1 LAST MATERIAL SPCAP
J 0
(-2675 2750);
DISPLAY 0.489362 (-2675 2750);
PAINT SKYBLUE (-2675 2750);
FORCEPROP 2 LAST CDS_LIB pure_quanta
J 0
(-2725 2850);
DISPLAY INVISIBLE (-2725 2850);
FORCEPROP 1 LAST PATH I58
J 0
(-2675 3000);
DISPLAY 0.978723 (-2675 3000);
DISPLAY INVISIBLE (-2675 3000);
FORCEPROP 1 LAST PART_NUMBER CH747LM8825
J 0
(-2675 2650);
DISPLAY 0.489362 (-2675 2650);
PAINT SKYBLUE (-2675 2650);
DISPLAY INVISIBLE (-2675 2650);
FORCEADD Q_CAPP..1
(-2400 2850);
FORCEPROP 1 LAST LOCATION PC226
J 0
(-2350 2950);
DISPLAY 0.489362 (-2350 2950);
PAINT SKYBLUE (-2350 2950);
FORCEPROP 0 LAST $SEC 1
J 0
(-2350 3000);
DISPLAY 0.680851 (-2350 3000);
PAINT MONO (-2350 3000);
DISPLAY INVISIBLE (-2350 3000);
FORCEPROP 0 LAST CDS_SEC 1
J 0
(-2350 3000);
DISPLAY 1.021277 (-2350 3000);
DISPLAY INVISIBLE (-2350 3000);
FORCEPROP 1 LASTPIN (-2400 2950) $PN 1
J 0
(-2390 2935);
DISPLAY 0.489362 (-2390 2935);
PAINT MONO (-2390 2935);
FORCEPROP 1 LASTPIN (-2400 2750) $PN 2
J 0
(-2390 2735);
DISPLAY 0.489362 (-2390 2735);
PAINT MONO (-2390 2735);
FORCEPROP 1 LAST VOLTAGE 2.5V
J 0
(-2350 2800);
DISPLAY 0.489362 (-2350 2800);
PAINT SKYBLUE (-2350 2800);
FORCEPROP 1 LAST TOLERANCE 20%
J 0
(-2350 2850);
DISPLAY 0.489362 (-2350 2850);
PAINT SKYBLUE (-2350 2850);
FORCEPROP 1 LAST PACK_TYPE SMLF
J 0
(-2350 2700);
DISPLAY 0.489362 (-2350 2700);
PAINT SKYBLUE (-2350 2700);
FORCEPROP 1 LAST VALUE 470UF
J 0
(-2350 2900);
DISPLAY 0.489362 (-2350 2900);
PAINT SKYBLUE (-2350 2900);
FORCEPROP 1 LAST MATERIAL SPCAP
J 0
(-2350 2750);
DISPLAY 0.489362 (-2350 2750);
PAINT SKYBLUE (-2350 2750);
FORCEPROP 2 LAST CDS_LIB pure_quanta
J 0
(-2400 2850);
DISPLAY INVISIBLE (-2400 2850);
FORCEPROP 1 LAST PATH I59
J 0
(-2350 3000);
DISPLAY 0.978723 (-2350 3000);
DISPLAY INVISIBLE (-2350 3000);
FORCEPROP 1 LAST PART_NUMBER CH747LM8825
J 0
(-2350 2650);
DISPLAY 0.489362 (-2350 2650);
PAINT SKYBLUE (-2350 2650);
DISPLAY INVISIBLE (-2350 2650);
FORCEADD OFFPAGE..2
R 2
(-7125 1000);
FORCEPROP 2 LAST $XR1 207 
J 0
(-7380 964);
DISPLAY 0.638298 (-7380 964);
PAINT MONO (-7380 964);
FORCEPROP 2 LAST $XR0 208 
J 0
(-7380 1000);
DISPLAY 0.638298 (-7380 1000);
PAINT MONO (-7380 1000);
FORCEPROP 2 LAST CDS_LIB standard
J 0
(-7125 1000);
DISPLAY INVISIBLE (-7125 1000);
FORCEPROP 1 LAST OFFPAGE TRUE
J 2
(-7450 875);
DISPLAY 0.872340 (-7450 875);
PAINT GREEN (-7450 875);
DISPLAY INVISIBLE (-7450 875);
FORCEPROP 1 LAST COMMENT_BODY TRUE
J 2
(-7080 905);
DISPLAY 0.872340 (-7080 905);
PAINT GREEN (-7080 905);
DISPLAY INVISIBLE (-7080 905);
FORCEPROP 2 LAST PATH I6
J 0
(-7400 1050);
DISPLAY 0.680851 (-7400 1050);
DISPLAY INVISIBLE (-7400 1050);
FORCEADD VCC_CORE..1
(-2725 3100);
FORCEPROP 3 LASTPIN (-2725 3050) SIG_NAME PVDD11_S3_P0\g
J 0
(-2715 3060);
DISPLAY 0.659574 (-2715 3060);
PAINT MONO (-2715 3060);
DISPLAY INVISIBLE (-2715 3060);
FORCEPROP 1 LAST HDL_POWER PVDD11_S3_P0
J 1
(-2725 3150);
DISPLAY 0.489362 (-2725 3150);
PAINT GREEN (-2725 3150);
FORCEPROP 2 LAST CDS_LIB pure_quanta_power
J 0
(-2725 3100);
DISPLAY INVISIBLE (-2725 3100);
FORCEPROP 1 LAST PATH I60
J 0
(-2675 3125);
DISPLAY 0.872340 (-2675 3125);
PAINT AQUA (-2675 3125);
DISPLAY INVISIBLE (-2675 3125);
FORCEADD UNIVERSAL_GND..1
(-1950 975);
FORCEPROP 3 LASTPIN (-1950 1025) SIG_NAME GND\g
J 0
(-1940 1035);
DISPLAY 0.659574 (-1940 1035);
PAINT MONO (-1940 1035);
DISPLAY INVISIBLE (-1940 1035);
FORCEPROP 2 LAST CDS_LIB pure_quanta_power
J 0
(-1950 975);
DISPLAY INVISIBLE (-1950 975);
FORCEPROP 1 LAST HDL_POWER GND
J 1
(-1925 900);
DISPLAY 0.872340 (-1925 900);
PAINT GREEN (-1925 900);
DISPLAY INVISIBLE (-1925 900);
FORCEPROP 1 LAST PATH I61
J 0
(-1875 975);
DISPLAY 0.872340 (-1875 975);
PAINT AQUA (-1875 975);
DISPLAY INVISIBLE (-1875 975);
FORCEADD Q_CAP..1
(-1950 1325);
FORCEPROP 1 LAST LOCATION PC225_2
J 0
(-1900 1425);
DISPLAY 0.489362 (-1900 1425);
PAINT SKYBLUE (-1900 1425);
FORCEPROP 0 LAST $SEC 1
J 0
(-1900 1450);
DISPLAY 0.680851 (-1900 1450);
PAINT MONO (-1900 1450);
DISPLAY INVISIBLE (-1900 1450);
FORCEPROP 0 LAST CDS_SEC 1
J 0
(-1900 1450);
DISPLAY 1.021277 (-1900 1450);
DISPLAY INVISIBLE (-1900 1450);
FORCEPROP 1 LASTPIN (-1950 1425) $PN 1
J 0
(-1940 1405);
DISPLAY 0.489362 (-1940 1405);
PAINT MONO (-1940 1405);
FORCEPROP 1 LASTPIN (-1950 1225) $PN 2
J 0
(-1940 1205);
DISPLAY 0.489362 (-1940 1205);
PAINT MONO (-1940 1205);
FORCEPROP 1 LAST PACK_TYPE C0805
J 0
(-1900 1125);
DISPLAY 0.489362 (-1900 1125);
PAINT SKYBLUE (-1900 1125);
FORCEPROP 1 LAST MATERIAL X6S
J 0
(-1900 1225);
DISPLAY 0.489362 (-1900 1225);
PAINT SKYBLUE (-1900 1225);
FORCEPROP 1 LAST TOLERANCE 20%
J 0
(-1900 1275);
DISPLAY 0.489362 (-1900 1275);
PAINT SKYBLUE (-1900 1275);
FORCEPROP 1 LAST VALUE 22UF
J 0
(-1900 1375);
DISPLAY 0.489362 (-1900 1375);
PAINT SKYBLUE (-1900 1375);
FORCEPROP 1 LAST VOLTAGE 4V
J 0
(-1900 1325);
DISPLAY 0.489362 (-1900 1325);
PAINT SKYBLUE (-1900 1325);
FORCEPROP 2 LAST CDS_LIB pure_quanta
J 0
(-1950 1325);
DISPLAY INVISIBLE (-1950 1325);
FORCEPROP 1 LAST PATH I62
J 0
(-1900 1475);
DISPLAY 0.978723 (-1900 1475);
PAINT WHITE (-1900 1475);
DISPLAY INVISIBLE (-1900 1475);
FORCEPROP 1 LAST PART_NUMBER CH622KMEA03
J 0
(-1900 1175);
DISPLAY 0.489362 (-1900 1175);
PAINT SKYBLUE (-1900 1175);
DISPLAY INVISIBLE (-1900 1175);
FORCEADD VCC_CORE..1
(-1950 1650);
FORCEPROP 3 LASTPIN (-1950 1600) SIG_NAME PVDD11_S3_P0\g
J 0
(-1940 1610);
DISPLAY 0.659574 (-1940 1610);
PAINT MONO (-1940 1610);
DISPLAY INVISIBLE (-1940 1610);
FORCEPROP 1 LAST HDL_POWER PVDD11_S3_P0
J 1
(-1950 1700);
DISPLAY 0.489362 (-1950 1700);
PAINT GREEN (-1950 1700);
FORCEPROP 2 LAST CDS_LIB pure_quanta_power
J 0
(-1950 1650);
DISPLAY INVISIBLE (-1950 1650);
FORCEPROP 1 LAST PATH I63
J 0
(-1900 1675);
DISPLAY 0.872340 (-1900 1675);
PAINT AQUA (-1900 1675);
DISPLAY INVISIBLE (-1900 1675);
FORCEADD UNIVERSAL_GND..1
(-1675 2550);
FORCEPROP 3 LASTPIN (-1675 2600) SIG_NAME GND\g
J 0
(-1665 2610);
DISPLAY 0.659574 (-1665 2610);
PAINT MONO (-1665 2610);
DISPLAY INVISIBLE (-1665 2610);
FORCEPROP 2 LAST CDS_LIB pure_quanta_power
J 0
(-1675 2550);
DISPLAY INVISIBLE (-1675 2550);
FORCEPROP 1 LAST HDL_POWER GND
J 1
(-1650 2475);
DISPLAY 0.872340 (-1650 2475);
PAINT GREEN (-1650 2475);
DISPLAY INVISIBLE (-1650 2475);
FORCEPROP 1 LAST PATH I64
J 0
(-1600 2550);
DISPLAY 0.872340 (-1600 2550);
PAINT AQUA (-1600 2550);
DISPLAY INVISIBLE (-1600 2550);
FORCEADD Q_CAPP..1
(-1675 2875);
FORCEPROP 1 LAST LOCATION PC228
J 0
(-1625 2975);
DISPLAY 0.489362 (-1625 2975);
PAINT SKYBLUE (-1625 2975);
FORCEPROP 0 LAST $SEC 1
J 0
(-1625 3025);
DISPLAY 0.680851 (-1625 3025);
PAINT MONO (-1625 3025);
DISPLAY INVISIBLE (-1625 3025);
FORCEPROP 0 LAST CDS_SEC 1
J 0
(-1625 3025);
DISPLAY 1.021277 (-1625 3025);
DISPLAY INVISIBLE (-1625 3025);
FORCEPROP 1 LASTPIN (-1675 2975) $PN 1
J 0
(-1665 2960);
DISPLAY 0.489362 (-1665 2960);
PAINT MONO (-1665 2960);
FORCEPROP 1 LASTPIN (-1675 2775) $PN 2
J 0
(-1665 2760);
DISPLAY 0.489362 (-1665 2760);
PAINT MONO (-1665 2760);
FORCEPROP 1 LAST MATERIAL ALUM
J 0
(-1625 2775);
DISPLAY 0.489362 (-1625 2775);
PAINT SKYBLUE (-1625 2775);
FORCEPROP 1 LAST VOLTAGE 2.5V
J 0
(-1625 2825);
DISPLAY 0.489362 (-1625 2825);
PAINT SKYBLUE (-1625 2825);
FORCEPROP 1 LAST PACK_TYPE SMLF
J 0
(-1625 2725);
DISPLAY 0.489362 (-1625 2725);
PAINT SKYBLUE (-1625 2725);
FORCEPROP 1 LAST TOLERANCE 20%
J 0
(-1625 2875);
DISPLAY 0.489362 (-1625 2875);
PAINT SKYBLUE (-1625 2875);
FORCEPROP 1 LAST VALUE 390UF
J 0
(-1625 2925);
DISPLAY 0.489362 (-1625 2925);
PAINT SKYBLUE (-1625 2925);
FORCEPROP 2 LAST CDS_LIB pure_quanta
J 0
(-1675 2875);
DISPLAY INVISIBLE (-1675 2875);
FORCEPROP 1 LAST PATH I65
J 0
(-1625 3025);
DISPLAY 0.978723 (-1625 3025);
DISPLAY INVISIBLE (-1625 3025);
FORCEPROP 1 LAST PART_NUMBER CC7390JMZ13
J 0
(-1625 2675);
DISPLAY 0.489362 (-1625 2675);
PAINT SKYBLUE (-1625 2675);
DISPLAY INVISIBLE (-1625 2675);
FORCEADD Q_CAPP..1
(-1350 2875);
FORCEPROP 1 LAST LOCATION PC229
J 0
(-1300 2975);
DISPLAY 0.489362 (-1300 2975);
PAINT SKYBLUE (-1300 2975);
FORCEPROP 0 LAST $SEC 1
J 0
(-1300 3025);
DISPLAY 0.680851 (-1300 3025);
PAINT MONO (-1300 3025);
DISPLAY INVISIBLE (-1300 3025);
FORCEPROP 0 LAST CDS_SEC 1
J 0
(-1300 3025);
DISPLAY 1.021277 (-1300 3025);
DISPLAY INVISIBLE (-1300 3025);
FORCEPROP 1 LASTPIN (-1350 2975) $PN 1
J 0
(-1340 2960);
DISPLAY 0.489362 (-1340 2960);
PAINT MONO (-1340 2960);
FORCEPROP 1 LASTPIN (-1350 2775) $PN 2
J 0
(-1340 2760);
DISPLAY 0.489362 (-1340 2760);
PAINT MONO (-1340 2760);
FORCEPROP 1 LAST VOLTAGE 2.5V
J 0
(-1300 2825);
DISPLAY 0.489362 (-1300 2825);
PAINT SKYBLUE (-1300 2825);
FORCEPROP 1 LAST MATERIAL ALUM
J 0
(-1300 2775);
DISPLAY 0.489362 (-1300 2775);
PAINT SKYBLUE (-1300 2775);
FORCEPROP 1 LAST TOLERANCE 20%
J 0
(-1300 2875);
DISPLAY 0.489362 (-1300 2875);
PAINT SKYBLUE (-1300 2875);
FORCEPROP 1 LAST VALUE 390UF
J 0
(-1300 2925);
DISPLAY 0.489362 (-1300 2925);
PAINT SKYBLUE (-1300 2925);
FORCEPROP 1 LAST PACK_TYPE SMLF
J 0
(-1300 2725);
DISPLAY 0.489362 (-1300 2725);
PAINT SKYBLUE (-1300 2725);
FORCEPROP 2 LAST CDS_LIB pure_quanta
J 0
(-1350 2875);
DISPLAY INVISIBLE (-1350 2875);
FORCEPROP 1 LAST PATH I66
J 0
(-1300 3025);
DISPLAY 0.978723 (-1300 3025);
DISPLAY INVISIBLE (-1300 3025);
FORCEPROP 1 LAST PART_NUMBER CC7390JMZ13
J 0
(-1325 2675);
DISPLAY 0.489362 (-1325 2675);
PAINT SKYBLUE (-1325 2675);
DISPLAY INVISIBLE (-1325 2675);
FORCEADD Q_CAPP..1
(-1050 2875);
FORCEPROP 1 LAST LOCATION PC230
J 0
(-1000 2975);
DISPLAY 0.489362 (-1000 2975);
PAINT SKYBLUE (-1000 2975);
FORCEPROP 0 LAST $SEC 1
J 0
(-1000 3025);
DISPLAY 0.680851 (-1000 3025);
PAINT MONO (-1000 3025);
DISPLAY INVISIBLE (-1000 3025);
FORCEPROP 0 LAST CDS_SEC 1
J 0
(-1000 3025);
DISPLAY 1.021277 (-1000 3025);
DISPLAY INVISIBLE (-1000 3025);
FORCEPROP 1 LASTPIN (-1050 2975) $PN 1
J 0
(-1040 2960);
DISPLAY 0.489362 (-1040 2960);
PAINT MONO (-1040 2960);
FORCEPROP 1 LASTPIN (-1050 2775) $PN 2
J 0
(-1040 2760);
DISPLAY 0.489362 (-1040 2760);
PAINT MONO (-1040 2760);
FORCEPROP 1 LAST PACK_TYPE SMLF
J 0
(-1000 2725);
DISPLAY 0.489362 (-1000 2725);
PAINT SKYBLUE (-1000 2725);
FORCEPROP 1 LAST MATERIAL ALUM
J 0
(-1000 2775);
DISPLAY 0.489362 (-1000 2775);
PAINT SKYBLUE (-1000 2775);
FORCEPROP 1 LAST TOLERANCE 20%
J 0
(-1000 2875);
DISPLAY 0.489362 (-1000 2875);
PAINT SKYBLUE (-1000 2875);
FORCEPROP 1 LAST VALUE 390UF
J 0
(-1000 2925);
DISPLAY 0.489362 (-1000 2925);
PAINT SKYBLUE (-1000 2925);
FORCEPROP 1 LAST VOLTAGE 2.5V
J 0
(-1000 2825);
DISPLAY 0.489362 (-1000 2825);
PAINT SKYBLUE (-1000 2825);
FORCEPROP 2 LAST CDS_LIB pure_quanta
J 0
(-1050 2875);
DISPLAY INVISIBLE (-1050 2875);
FORCEPROP 1 LAST PATH I67
J 0
(-1000 3025);
DISPLAY 0.978723 (-1000 3025);
DISPLAY INVISIBLE (-1000 3025);
FORCEPROP 1 LAST PART_NUMBER CC7390JMZ13
J 0
(-1000 2675);
DISPLAY 0.489362 (-1000 2675);
PAINT SKYBLUE (-1000 2675);
DISPLAY INVISIBLE (-1000 2675);
FORCEADD VCC_CORE..1
(-1675 3100);
FORCEPROP 3 LASTPIN (-1675 3050) SIG_NAME PVDD11_S3_P0\g
J 0
(-1665 3060);
DISPLAY 0.659574 (-1665 3060);
PAINT MONO (-1665 3060);
DISPLAY INVISIBLE (-1665 3060);
FORCEPROP 1 LAST HDL_POWER PVDD11_S3_P0
J 1
(-1675 3150);
DISPLAY 0.489362 (-1675 3150);
PAINT GREEN (-1675 3150);
FORCEPROP 2 LAST CDS_LIB pure_quanta_power
J 0
(-1675 3100);
DISPLAY INVISIBLE (-1675 3100);
FORCEPROP 1 LAST PATH I68
J 0
(-1625 3125);
DISPLAY 0.872340 (-1625 3125);
PAINT AQUA (-1625 3125);
DISPLAY INVISIBLE (-1625 3125);
FORCEADD UNIVERSAL_GND..1
(-1200 3925);
FORCEPROP 3 LASTPIN (-1200 3975) SIG_NAME GND\g
J 0
(-1190 3985);
DISPLAY 0.659574 (-1190 3985);
PAINT MONO (-1190 3985);
DISPLAY INVISIBLE (-1190 3985);
FORCEPROP 2 LAST CDS_LIB pure_quanta_power
J 0
(-1200 3925);
DISPLAY INVISIBLE (-1200 3925);
FORCEPROP 1 LAST HDL_POWER GND
J 1
(-1175 3850);
DISPLAY 0.872340 (-1175 3850);
PAINT GREEN (-1175 3850);
DISPLAY INVISIBLE (-1175 3850);
FORCEPROP 1 LAST PATH I69
J 0
(-1125 3925);
DISPLAY 0.872340 (-1125 3925);
PAINT AQUA (-1125 3925);
DISPLAY INVISIBLE (-1125 3925);
FORCEADD Q_CAP..1
(-7825 1225);
FORCEPROP 1 LAST LOCATION PC202_2
J 0
(-7775 1325);
DISPLAY 0.489362 (-7775 1325);
PAINT SKYBLUE (-7775 1325);
FORCEPROP 0 LAST $SEC 1
J 0
(-7775 1350);
DISPLAY 0.680851 (-7775 1350);
PAINT MONO (-7775 1350);
DISPLAY INVISIBLE (-7775 1350);
FORCEPROP 0 LAST CDS_SEC 1
J 0
(-7775 1350);
DISPLAY 1.021277 (-7775 1350);
DISPLAY INVISIBLE (-7775 1350);
FORCEPROP 1 LASTPIN (-7825 1325) $PN 1
J 0
(-7815 1305);
DISPLAY 0.489362 (-7815 1305);
PAINT MONO (-7815 1305);
FORCEPROP 1 LASTPIN (-7825 1125) $PN 2
J 0
(-7815 1105);
DISPLAY 0.489362 (-7815 1105);
PAINT MONO (-7815 1105);
FORCEPROP 1 LAST PACK_TYPE 0402
J 0
(-7775 1025);
DISPLAY 0.489362 (-7775 1025);
PAINT SKYBLUE (-7775 1025);
FORCEPROP 1 LAST VOLTAGE 25V
J 0
(-7775 1225);
DISPLAY 0.489362 (-7775 1225);
PAINT SKYBLUE (-7775 1225);
FORCEPROP 1 LAST VALUE 0.1UF
J 0
(-7775 1275);
DISPLAY 0.489362 (-7775 1275);
PAINT SKYBLUE (-7775 1275);
FORCEPROP 1 LAST TOLERANCE 10%
J 0
(-7775 1175);
DISPLAY 0.489362 (-7775 1175);
PAINT SKYBLUE (-7775 1175);
FORCEPROP 1 LAST MATERIAL X7R
J 0
(-7775 1125);
DISPLAY 0.489362 (-7775 1125);
PAINT SKYBLUE (-7775 1125);
FORCEPROP 2 LAST CDS_LIB pure_quanta
J 0
(-7825 1225);
DISPLAY INVISIBLE (-7825 1225);
FORCEPROP 1 LAST PATH I7
J 0
(-7775 1375);
DISPLAY 0.978723 (-7775 1375);
PAINT WHITE (-7775 1375);
DISPLAY INVISIBLE (-7775 1375);
FORCEPROP 1 LAST PART_NUMBER CH4104K1B00
J 0
(-7775 1075);
DISPLAY 0.489362 (-7775 1075);
PAINT SKYBLUE (-7775 1075);
DISPLAY INVISIBLE (-7775 1075);
FORCEADD Q_CAPP..1
(-700 2875);
FORCEPROP 1 LAST LOCATION PC801
J 0
(-650 2975);
DISPLAY 0.489362 (-650 2975);
PAINT SKYBLUE (-650 2975);
FORCEPROP 0 LAST $SEC 1
J 0
(-650 3000);
DISPLAY 0.680851 (-650 3000);
PAINT MONO (-650 3000);
DISPLAY INVISIBLE (-650 3000);
FORCEPROP 0 LAST CDS_SEC 1
J 0
(-650 3000);
DISPLAY 0.680851 (-650 3000);
DISPLAY INVISIBLE (-650 3000);
FORCEPROP 1 LASTPIN (-700 2975) $PN 1
J 0
(-690 2960);
DISPLAY 0.489362 (-690 2960);
PAINT MONO (-690 2960);
FORCEPROP 1 LASTPIN (-700 2775) $PN 2
J 0
(-690 2760);
DISPLAY 0.489362 (-690 2760);
PAINT MONO (-690 2760);
FORCEPROP 1 LAST MATERIAL ALUM
J 0
(-650 2775);
DISPLAY 0.489362 (-650 2775);
PAINT SKYBLUE (-650 2775);
FORCEPROP 1 LAST TOLERANCE 20%
J 0
(-650 2875);
DISPLAY 0.489362 (-650 2875);
PAINT SKYBLUE (-650 2875);
FORCEPROP 1 LAST VALUE 390UF
J 0
(-650 2925);
DISPLAY 0.489362 (-650 2925);
PAINT SKYBLUE (-650 2925);
FORCEPROP 1 LAST VOLTAGE 2.5V
J 0
(-650 2825);
DISPLAY 0.489362 (-650 2825);
PAINT SKYBLUE (-650 2825);
FORCEPROP 1 LAST PACK_TYPE SMLF
J 0
(-650 2725);
DISPLAY 0.489362 (-650 2725);
PAINT SKYBLUE (-650 2725);
FORCEPROP 2 LAST CDS_LIB pure_quanta
J 0
(-700 2875);
DISPLAY INVISIBLE (-700 2875);
FORCEPROP 1 LAST PATH I70
J 0
(-650 3025);
DISPLAY 0.978723 (-650 3025);
DISPLAY INVISIBLE (-650 3025);
FORCEPROP 1 LAST PART_NUMBER CC7390JMZ13
J 0
(-650 2675);
DISPLAY 0.489362 (-650 2675);
PAINT SKYBLUE (-650 2675);
DISPLAY INVISIBLE (-650 2675);
FORCEADD Q_CAP..1
(-3925 4650);
FORCEPROP 1 LAST LOCATION PC217
J 0
(-3875 4775);
DISPLAY 0.489362 (-3875 4775);
PAINT SKYBLUE (-3875 4775);
FORCEPROP 0 LAST $SEC 1
J 0
(-3875 4800);
DISPLAY 0.680851 (-3875 4800);
PAINT MONO (-3875 4800);
DISPLAY INVISIBLE (-3875 4800);
FORCEPROP 0 LAST CDS_SEC 1
J 0
(-3875 4800);
DISPLAY 1.021277 (-3875 4800);
DISPLAY INVISIBLE (-3875 4800);
FORCEPROP 1 LASTPIN (-3925 4750) $PN 1
J 0
(-3915 4730);
DISPLAY 0.489362 (-3915 4730);
PAINT MONO (-3915 4730);
FORCEPROP 1 LASTPIN (-3925 4550) $PN 2
J 0
(-3915 4530);
DISPLAY 0.489362 (-3915 4530);
PAINT MONO (-3915 4530);
FORCEPROP 1 LAST TOLERANCE 10%
J 0
(-3875 4625);
DISPLAY 0.489362 (-3875 4625);
PAINT SKYBLUE (-3875 4625);
FORCEPROP 1 LAST PACK_TYPE 0402
J 0
(-3875 4475);
DISPLAY 0.489362 (-3875 4475);
PAINT SKYBLUE (-3875 4475);
FORCEPROP 1 LAST VALUE 0.22UF
J 0
(-3875 4725);
DISPLAY 0.489362 (-3875 4725);
PAINT SKYBLUE (-3875 4725);
FORCEPROP 1 LAST VOLTAGE 16V
J 0
(-3875 4675);
DISPLAY 0.489362 (-3875 4675);
PAINT SKYBLUE (-3875 4675);
FORCEPROP 1 LAST MATERIAL X7R
J 0
(-3875 4575);
DISPLAY 0.489362 (-3875 4575);
PAINT SKYBLUE (-3875 4575);
FORCEPROP 2 LAST CDS_LIB pure_quanta
J 0
(-3925 4650);
DISPLAY INVISIBLE (-3925 4650);
FORCEPROP 1 LAST PATH I71
J 0
(-3875 4800);
DISPLAY 0.978723 (-3875 4800);
PAINT WHITE (-3875 4800);
DISPLAY INVISIBLE (-3875 4800);
FORCEPROP 1 LAST PART_NUMBER CH4223K1B00
J 0
(-3875 4525);
DISPLAY 0.489362 (-3875 4525);
PAINT SKYBLUE (-3875 4525);
DISPLAY INVISIBLE (-3875 4525);
FORCEADD UNIVERSAL_GND..1
(-3900 5000);
FORCEPROP 3 LASTPIN (-3900 5050) SIG_NAME GND\g
J 0
(-3890 5060);
DISPLAY 0.659574 (-3890 5060);
PAINT MONO (-3890 5060);
DISPLAY INVISIBLE (-3890 5060);
FORCEPROP 2 LAST CDS_LIB pure_quanta_power
J 0
(-3900 5000);
DISPLAY INVISIBLE (-3900 5000);
FORCEPROP 1 LAST HDL_POWER GND
J 1
(-3875 4925);
DISPLAY 0.872340 (-3875 4925);
PAINT GREEN (-3875 4925);
DISPLAY INVISIBLE (-3875 4925);
FORCEPROP 1 LAST PATH I72
J 0
(-3825 5000);
DISPLAY 0.872340 (-3825 5000);
PAINT AQUA (-3825 5000);
DISPLAY INVISIBLE (-3825 5000);
FORCEADD Q_INDUCTOR..1
(-3275 4450);
FORCEPROP 1 LAST LOCATION PL23
J 0
(-3300 4500);
DISPLAY 0.489362 (-3300 4500);
PAINT SKYBLUE (-3300 4500);
FORCEPROP 0 LAST $SEC 1
J 0
(-3300 4525);
DISPLAY 0.680851 (-3300 4525);
PAINT MONO (-3300 4525);
DISPLAY INVISIBLE (-3300 4525);
FORCEPROP 0 LAST CDS_SEC 1
J 0
(-3300 4525);
DISPLAY 1.021277 (-3300 4525);
DISPLAY INVISIBLE (-3300 4525);
FORCEPROP 0 LASTPIN (-3375 4425) $PN 1
J 2
(-3385 4435);
DISPLAY 0.489362 (-3385 4435);
PAINT MONO (-3385 4435);
FORCEPROP 0 LASTPIN (-3175 4425) $PN 2
J 0
(-3165 4435);
DISPLAY 0.489362 (-3165 4435);
PAINT MONO (-3165 4435);
FORCEPROP 2 LAST PACK_TYPE SMLF
J 0
(-3375 4225);
DISPLAY 0.489362 (-3375 4225);
PAINT SKYBLUE (-3375 4225);
FORCEPROP 1 LAST MATERIAL IND
J 0
(-3375 4275);
DISPLAY 0.489362 (-3375 4275);
PAINT SKYBLUE (-3375 4275);
FORCEPROP 2 LAST VALUE 90NH/155A
J 0
(-3375 4375);
DISPLAY 0.489362 (-3375 4375);
PAINT SKYBLUE (-3375 4375);
FORCEPROP 2 LAST CDS_LIB pure_quanta
J 0
(-3275 4450);
DISPLAY INVISIBLE (-3275 4450);
FORCEPROP 1 LAST NEEDS_NO_SIZE TRUE
J 0
(-3275 4450);
DISPLAY 0.468085 (-3275 4450);
PAINT GREEN (-3275 4450);
DISPLAY INVISIBLE (-3275 4450);
FORCEPROP 1 LAST PATH I73
J 0
(-3200 4505);
DISPLAY 0.723404 (-3200 4505);
PAINT GREEN (-3200 4505);
DISPLAY INVISIBLE (-3200 4505);
FORCEPROP 1 LAST PART_NUMBER CVA90^0KZ13
J 0
(-3375 4325);
DISPLAY 0.489362 (-3375 4325);
PAINT SKYBLUE (-3375 4325);
DISPLAY INVISIBLE (-3375 4325);
FORCEADD VCC_CORE..1
(-3900 5675);
FORCEPROP 3 LASTPIN (-3900 5625) SIG_NAME SW_P12V_AUX_PVDD11_S3_P0_FLT\g
J 0
(-3890 5635);
DISPLAY 0.659574 (-3890 5635);
PAINT MONO (-3890 5635);
DISPLAY INVISIBLE (-3890 5635);
FORCEPROP 1 LAST HDL_POWER SW_P12V_AUX_PVDD11_S3_P0_FLT
J 1
(-3900 5725);
DISPLAY 0.489362 (-3900 5725);
PAINT GREEN (-3900 5725);
FORCEPROP 2 LAST CDS_LIB pure_quanta_power
J 0
(-3900 5675);
DISPLAY INVISIBLE (-3900 5675);
FORCEPROP 1 LAST PATH I74
J 0
(-3850 5700);
DISPLAY 0.872340 (-3850 5700);
PAINT AQUA (-3850 5700);
DISPLAY INVISIBLE (-3850 5700);
FORCEADD Q_CAPP..1
(-3250 5325);
FORCEPROP 1 LAST LOCATION PC220
J 0
(-3200 5425);
DISPLAY 0.489362 (-3200 5425);
PAINT SKYBLUE (-3200 5425);
FORCEPROP 0 LAST $SEC 1
J 0
(-3200 5450);
DISPLAY 0.680851 (-3200 5450);
PAINT MONO (-3200 5450);
DISPLAY INVISIBLE (-3200 5450);
FORCEPROP 0 LAST CDS_SEC 1
J 0
(-3200 5450);
DISPLAY 1.021277 (-3200 5450);
DISPLAY INVISIBLE (-3200 5450);
FORCEPROP 1 LASTPIN (-3250 5425) $PN 1
J 0
(-3240 5410);
DISPLAY 0.489362 (-3240 5410);
PAINT MONO (-3240 5410);
FORCEPROP 1 LASTPIN (-3250 5225) $PN 2
J 0
(-3240 5210);
DISPLAY 0.489362 (-3240 5210);
PAINT MONO (-3240 5210);
FORCEPROP 1 LAST MATERIAL OSCON
J 0
(-3200 5225);
DISPLAY 0.489362 (-3200 5225);
PAINT SKYBLUE (-3200 5225);
FORCEPROP 1 LAST VOLTAGE 16V
J 0
(-3200 5275);
DISPLAY 0.489362 (-3200 5275);
PAINT SKYBLUE (-3200 5275);
FORCEPROP 1 LAST PACK_TYPE THLF
J 0
(-3200 5175);
DISPLAY 0.489362 (-3200 5175);
PAINT SKYBLUE (-3200 5175);
FORCEPROP 1 LAST TOLERANCE 20%
J 0
(-3200 5325);
DISPLAY 0.489362 (-3200 5325);
PAINT SKYBLUE (-3200 5325);
FORCEPROP 1 LAST VALUE 270UF
J 0
(-3200 5375);
DISPLAY 0.489362 (-3200 5375);
PAINT SKYBLUE (-3200 5375);
FORCEPROP 2 LAST CDS_LIB pure_quanta
J 0
(-3250 5325);
DISPLAY INVISIBLE (-3250 5325);
FORCEPROP 1 LAST PATH I75
J 0
(-3200 5475);
DISPLAY 0.978723 (-3200 5475);
DISPLAY INVISIBLE (-3200 5475);
FORCEPROP 1 LAST PART_NUMBER CC72703MD38
J 0
(-3200 5125);
DISPLAY 0.489362 (-3200 5125);
PAINT SKYBLUE (-3200 5125);
DISPLAY INVISIBLE (-3200 5125);
FORCEADD Q_CAP..1
(-2300 4250);
FORCEPROP 1 LAST LOCATION PC222
J 0
(-2250 4350);
DISPLAY 0.489362 (-2250 4350);
PAINT SKYBLUE (-2250 4350);
FORCEPROP 0 LAST $SEC 1
J 0
(-2250 4375);
DISPLAY 0.680851 (-2250 4375);
PAINT MONO (-2250 4375);
DISPLAY INVISIBLE (-2250 4375);
FORCEPROP 0 LAST CDS_SEC 1
J 0
(-2250 4375);
DISPLAY 1.021277 (-2250 4375);
DISPLAY INVISIBLE (-2250 4375);
FORCEPROP 1 LASTPIN (-2300 4350) $PN 1
J 0
(-2290 4330);
DISPLAY 0.489362 (-2290 4330);
PAINT MONO (-2290 4330);
FORCEPROP 1 LASTPIN (-2300 4150) $PN 2
J 0
(-2290 4130);
DISPLAY 0.489362 (-2290 4130);
PAINT MONO (-2290 4130);
FORCEPROP 1 LAST PACK_TYPE 0402
J 0
(-2250 4050);
DISPLAY 0.489362 (-2250 4050);
PAINT SKYBLUE (-2250 4050);
FORCEPROP 1 LAST VALUE 0.1UF
J 0
(-2250 4300);
DISPLAY 0.489362 (-2250 4300);
PAINT SKYBLUE (-2250 4300);
FORCEPROP 1 LAST TOLERANCE 10%
J 0
(-2250 4200);
DISPLAY 0.489362 (-2250 4200);
PAINT SKYBLUE (-2250 4200);
FORCEPROP 1 LAST MATERIAL X7R
J 0
(-2250 4150);
DISPLAY 0.489362 (-2250 4150);
PAINT SKYBLUE (-2250 4150);
FORCEPROP 1 LAST VOLTAGE 25V
J 0
(-2250 4250);
DISPLAY 0.489362 (-2250 4250);
PAINT SKYBLUE (-2250 4250);
FORCEPROP 2 LAST CDS_LIB pure_quanta
J 0
(-2300 4250);
DISPLAY INVISIBLE (-2300 4250);
FORCEPROP 1 LAST PATH I76
J 0
(-2250 4400);
DISPLAY 0.978723 (-2250 4400);
PAINT WHITE (-2250 4400);
DISPLAY INVISIBLE (-2250 4400);
FORCEPROP 1 LAST PART_NUMBER CH4104K1B00
J 0
(-2250 4100);
DISPLAY 0.489362 (-2250 4100);
PAINT SKYBLUE (-2250 4100);
DISPLAY INVISIBLE (-2250 4100);
FORCEADD UNIVERSAL_GND..1
(-2275 4975);
FORCEPROP 3 LASTPIN (-2275 5025) SIG_NAME GND\g
J 0
(-2265 5035);
DISPLAY 0.659574 (-2265 5035);
PAINT MONO (-2265 5035);
DISPLAY INVISIBLE (-2265 5035);
FORCEPROP 2 LAST CDS_LIB pure_quanta_power
J 0
(-2275 4975);
DISPLAY INVISIBLE (-2275 4975);
FORCEPROP 1 LAST HDL_POWER GND
J 1
(-2250 4900);
DISPLAY 0.872340 (-2250 4900);
PAINT GREEN (-2250 4900);
DISPLAY INVISIBLE (-2250 4900);
FORCEPROP 1 LAST PATH I77
J 0
(-2200 4975);
DISPLAY 0.872340 (-2200 4975);
PAINT AQUA (-2200 4975);
DISPLAY INVISIBLE (-2200 4975);
FORCEADD Q_INDUCTOR..1
(-2900 5525);
FORCEPROP 1 LAST LOCATION PL24
J 0
(-3025 5685);
DISPLAY 0.489362 (-3025 5685);
PAINT SKYBLUE (-3025 5685);
FORCEPROP 0 LAST $SEC 1
J 0
(-3025 5800);
DISPLAY 0.680851 (-3025 5800);
PAINT MONO (-3025 5800);
DISPLAY INVISIBLE (-3025 5800);
FORCEPROP 0 LAST CDS_SEC 1
J 0
(-3025 5800);
DISPLAY 1.021277 (-3025 5800);
DISPLAY INVISIBLE (-3025 5800);
FORCEPROP 0 LASTPIN (-3000 5500) $PN 1
J 2
(-3010 5510);
DISPLAY 0.489362 (-3010 5510);
PAINT MONO (-3010 5510);
FORCEPROP 0 LASTPIN (-2800 5500) $PN 2
J 0
(-2790 5510);
DISPLAY 0.489362 (-2790 5510);
PAINT MONO (-2790 5510);
FORCEPROP 1 LAST MATERIAL IND
J 0
(-3025 5580);
DISPLAY 0.489362 (-3025 5580);
PAINT SKYBLUE (-3025 5580);
FORCEPROP 2 LAST VALUE 100NH/16A
J 0
(-3025 5775);
DISPLAY 0.489362 (-3025 5775);
PAINT SKYBLUE (-3025 5775);
FORCEPROP 2 LAST PACK_TYPE SMLF
J 0
(-3025 5725);
DISPLAY 0.489362 (-3025 5725);
PAINT SKYBLUE (-3025 5725);
FORCEPROP 2 LAST CDS_LIB pure_quanta
J 0
(-2900 5525);
DISPLAY INVISIBLE (-2900 5525);
FORCEPROP 1 LAST NEEDS_NO_SIZE TRUE
J 0
(-2900 5525);
DISPLAY 0.468085 (-2900 5525);
PAINT GREEN (-2900 5525);
DISPLAY INVISIBLE (-2900 5525);
FORCEPROP 1 LAST PATH I78
J 0
(-2825 5580);
DISPLAY 0.723404 (-2825 5580);
PAINT GREEN (-2825 5580);
DISPLAY INVISIBLE (-2825 5580);
FORCEPROP 1 LAST PART_NUMBER CV+10G0MZ04
J 0
(-3025 5635);
DISPLAY 0.489362 (-3025 5635);
PAINT SKYBLUE (-3025 5635);
DISPLAY INVISIBLE (-3025 5635);
FORCEADD Q_CAP..1
(-2275 5300);
FORCEPROP 1 LAST LOCATION PC6003
J 0
(-2225 5400);
DISPLAY 0.489362 (-2225 5400);
PAINT SKYBLUE (-2225 5400);
FORCEPROP 0 LAST $SEC 1
J 0
(-2225 5425);
DISPLAY 0.680851 (-2225 5425);
PAINT MONO (-2225 5425);
DISPLAY INVISIBLE (-2225 5425);
FORCEPROP 0 LAST CDS_SEC 1
J 0
(-2225 5425);
DISPLAY 0.680851 (-2225 5425);
DISPLAY INVISIBLE (-2225 5425);
FORCEPROP 1 LASTPIN (-2275 5400) $PN 1
J 0
(-2265 5380);
DISPLAY 0.787234 (-2265 5380);
PAINT MONO (-2265 5380);
FORCEPROP 1 LASTPIN (-2275 5200) $PN 2
J 0
(-2265 5180);
DISPLAY 0.787234 (-2265 5180);
PAINT MONO (-2265 5180);
FORCEPROP 1 LAST VOLTAGE 25V
J 0
(-2225 5300);
DISPLAY 0.489362 (-2225 5300);
PAINT SKYBLUE (-2225 5300);
FORCEPROP 1 LAST TOLERANCE 10%
J 0
(-2225 5250);
DISPLAY 0.489362 (-2225 5250);
PAINT SKYBLUE (-2225 5250);
FORCEPROP 1 LAST MATERIAL X7R
J 0
(-2225 5200);
DISPLAY 0.489362 (-2225 5200);
PAINT SKYBLUE (-2225 5200);
FORCEPROP 1 LAST VALUE 0.1UF
J 0
(-2225 5350);
DISPLAY 0.489362 (-2225 5350);
PAINT SKYBLUE (-2225 5350);
FORCEPROP 1 LAST PACK_TYPE 0402
J 0
(-2225 5100);
DISPLAY 0.489362 (-2225 5100);
PAINT SKYBLUE (-2225 5100);
FORCEPROP 2 LAST CDS_LIB pure_quanta
J 0
(-2275 5300);
DISPLAY INVISIBLE (-2275 5300);
FORCEPROP 1 LAST PATH I79
J 0
(-2225 5450);
DISPLAY 0.978723 (-2225 5450);
PAINT WHITE (-2225 5450);
DISPLAY INVISIBLE (-2225 5450);
FORCEPROP 1 LAST PART_NUMBER CH4104K1B00
J 0
(-2225 5150);
DISPLAY 0.489362 (-2225 5150);
PAINT SKYBLUE (-2225 5150);
DISPLAY INVISIBLE (-2225 5150);
FORCEADD UNIVERSAL_GND..1
(-7775 1625);
FORCEPROP 3 LASTPIN (-7775 1675) SIG_NAME GND\g
J 0
(-7765 1685);
DISPLAY 0.659574 (-7765 1685);
PAINT MONO (-7765 1685);
DISPLAY INVISIBLE (-7765 1685);
FORCEPROP 2 LAST CDS_LIB pure_quanta_power
J 0
(-7775 1625);
DISPLAY INVISIBLE (-7775 1625);
FORCEPROP 1 LAST HDL_POWER GND
J 1
(-7750 1550);
DISPLAY 0.872340 (-7750 1550);
PAINT GREEN (-7750 1550);
DISPLAY INVISIBLE (-7750 1550);
FORCEPROP 1 LAST PATH I8
J 0
(-7700 1625);
DISPLAY 0.872340 (-7700 1625);
PAINT AQUA (-7700 1625);
DISPLAY INVISIBLE (-7700 1625);
FORCEADD VCC_CORE..1
(-2275 5700);
FORCEPROP 3 LASTPIN (-2275 5650) SIG_NAME P12V_AUX\g
J 0
(-2265 5660);
DISPLAY 0.659574 (-2265 5660);
PAINT MONO (-2265 5660);
DISPLAY INVISIBLE (-2265 5660);
FORCEPROP 1 LAST HDL_POWER P12V_AUX
J 1
(-2275 5750);
DISPLAY 0.489362 (-2275 5750);
PAINT GREEN (-2275 5750);
FORCEPROP 2 LAST CDS_LIB pure_quanta_power
J 0
(-2275 5700);
DISPLAY INVISIBLE (-2275 5700);
FORCEPROP 1 LAST PATH I80
J 0
(-2225 5725);
DISPLAY 0.872340 (-2225 5725);
PAINT AQUA (-2225 5725);
DISPLAY INVISIBLE (-2225 5725);
FORCEADD Q_CAP..1
(-1950 4250);
FORCEPROP 1 LAST LOCATION PC224_1
J 0
(-1900 4350);
DISPLAY 0.489362 (-1900 4350);
PAINT SKYBLUE (-1900 4350);
FORCEPROP 0 LAST $SEC 1
J 0
(-1900 4375);
DISPLAY 0.680851 (-1900 4375);
PAINT MONO (-1900 4375);
DISPLAY INVISIBLE (-1900 4375);
FORCEPROP 0 LAST CDS_SEC 1
J 0
(-1900 4375);
DISPLAY 1.021277 (-1900 4375);
DISPLAY INVISIBLE (-1900 4375);
FORCEPROP 1 LASTPIN (-1950 4350) $PN 1
J 0
(-1940 4330);
DISPLAY 0.489362 (-1940 4330);
PAINT MONO (-1940 4330);
FORCEPROP 1 LASTPIN (-1950 4150) $PN 2
J 0
(-1940 4130);
DISPLAY 0.489362 (-1940 4130);
PAINT MONO (-1940 4130);
FORCEPROP 1 LAST PACK_TYPE C0805
J 0
(-1900 4050);
DISPLAY 0.489362 (-1900 4050);
PAINT SKYBLUE (-1900 4050);
FORCEPROP 1 LAST MATERIAL X6S
J 0
(-1900 4150);
DISPLAY 0.489362 (-1900 4150);
PAINT SKYBLUE (-1900 4150);
FORCEPROP 1 LAST TOLERANCE 20%
J 0
(-1900 4200);
DISPLAY 0.489362 (-1900 4200);
PAINT SKYBLUE (-1900 4200);
FORCEPROP 1 LAST VALUE 22UF
J 0
(-1900 4300);
DISPLAY 0.489362 (-1900 4300);
PAINT SKYBLUE (-1900 4300);
FORCEPROP 1 LAST VOLTAGE 4V
J 0
(-1900 4250);
DISPLAY 0.489362 (-1900 4250);
PAINT SKYBLUE (-1900 4250);
FORCEPROP 2 LAST CDS_LIB pure_quanta
J 0
(-1950 4250);
DISPLAY INVISIBLE (-1950 4250);
FORCEPROP 1 LAST PATH I81
J 0
(-1900 4400);
DISPLAY 0.978723 (-1900 4400);
PAINT WHITE (-1900 4400);
DISPLAY INVISIBLE (-1900 4400);
FORCEPROP 1 LAST PART_NUMBER CH622KMEA03
J 0
(-1900 4100);
DISPLAY 0.489362 (-1900 4100);
PAINT SKYBLUE (-1900 4100);
DISPLAY INVISIBLE (-1900 4100);
FORCEADD Q_CAP..1
(-1525 4250);
FORCEPROP 1 LAST LOCATION PC227_1
J 0
(-1475 4350);
DISPLAY 0.489362 (-1475 4350);
PAINT SKYBLUE (-1475 4350);
FORCEPROP 0 LAST $SEC 1
J 0
(-1475 4375);
DISPLAY 0.680851 (-1475 4375);
PAINT MONO (-1475 4375);
DISPLAY INVISIBLE (-1475 4375);
FORCEPROP 0 LAST CDS_SEC 1
J 0
(-1475 4375);
DISPLAY 1.021277 (-1475 4375);
DISPLAY INVISIBLE (-1475 4375);
FORCEPROP 1 LASTPIN (-1525 4350) $PN 1
J 0
(-1515 4330);
DISPLAY 0.489362 (-1515 4330);
PAINT MONO (-1515 4330);
FORCEPROP 1 LASTPIN (-1525 4150) $PN 2
J 0
(-1515 4130);
DISPLAY 0.489362 (-1515 4130);
PAINT MONO (-1515 4130);
FORCEPROP 1 LAST PACK_TYPE C0805
J 0
(-1475 4100);
DISPLAY 0.489362 (-1475 4100);
PAINT SKYBLUE (-1475 4100);
FORCEPROP 1 LAST MATERIAL X6S
J 0
(-1475 4150);
DISPLAY 0.489362 (-1475 4150);
PAINT SKYBLUE (-1475 4150);
FORCEPROP 1 LAST TOLERANCE 20%
J 0
(-1475 4200);
DISPLAY 0.489362 (-1475 4200);
PAINT SKYBLUE (-1475 4200);
FORCEPROP 1 LAST VALUE 22UF
J 0
(-1475 4300);
DISPLAY 0.489362 (-1475 4300);
PAINT SKYBLUE (-1475 4300);
FORCEPROP 1 LAST VOLTAGE 4V
J 0
(-1475 4250);
DISPLAY 0.489362 (-1475 4250);
PAINT SKYBLUE (-1475 4250);
FORCEPROP 2 LAST CDS_LIB pure_quanta
J 0
(-1525 4250);
DISPLAY INVISIBLE (-1525 4250);
FORCEPROP 1 LAST PATH I82
J 0
(-1475 4400);
DISPLAY 0.978723 (-1475 4400);
PAINT WHITE (-1475 4400);
DISPLAY INVISIBLE (-1475 4400);
FORCEPROP 1 LAST PART_NUMBER CH622KMEA03
J 0
(-1475 4100);
DISPLAY 0.489362 (-1475 4100);
PAINT SKYBLUE (-1475 4100);
DISPLAY INVISIBLE (-1475 4100);
FORCEADD Q_RES..2
(-1200 4225);
FORCEPROP 1 LAST LOCATION PR414
J 0
(-1155 4350);
DISPLAY 0.489362 (-1155 4350);
PAINT SKYBLUE (-1155 4350);
FORCEPROP 0 LAST $SEC 1
J 0
(-1150 4375);
DISPLAY 0.680851 (-1150 4375);
PAINT MONO (-1150 4375);
DISPLAY INVISIBLE (-1150 4375);
FORCEPROP 0 LAST CDS_SEC 1
J 0
(-1150 4375);
DISPLAY 1.021277 (-1150 4375);
DISPLAY INVISIBLE (-1150 4375);
FORCEPROP 1 LASTPIN (-1200 4325) $PN 1
J 0
(-1195 4287);
DISPLAY 0.787234 (-1195 4287);
PAINT MONO (-1195 4287);
DISPLAY INVISIBLE (-1195 4287);
FORCEPROP 1 LASTPIN (-1200 4125) $PN 2
J 0
(-1195 4135);
DISPLAY 0.787234 (-1195 4135);
PAINT MONO (-1195 4135);
DISPLAY INVISIBLE (-1195 4135);
FORCEPROP 1 LAST WATTAGE 1/16W
J 0
(-1160 4200);
DISPLAY 0.489362 (-1160 4200);
PAINT SKYBLUE (-1160 4200);
FORCEPROP 1 LAST MATERIAL CHIP
J 0
(-1160 4150);
DISPLAY 0.489362 (-1160 4150);
PAINT SKYBLUE (-1160 4150);
FORCEPROP 1 LAST TOLERANCE 1%
J 0
(-1155 4250);
DISPLAY 0.489362 (-1155 4250);
PAINT SKYBLUE (-1155 4250);
FORCEPROP 1 LAST VALUE 1K
J 0
(-1155 4300);
DISPLAY 0.489362 (-1155 4300);
PAINT SKYBLUE (-1155 4300);
FORCEPROP 1 LAST PACK_TYPE 0402LF
J 0
(-1160 4050);
DISPLAY 0.489362 (-1160 4050);
PAINT SKYBLUE (-1160 4050);
FORCEPROP 2 LAST CDS_LIB pure_quanta
J 0
(-1200 4225);
DISPLAY INVISIBLE (-1200 4225);
FORCEPROP 1 LAST PATH I83
J 0
(-1150 4400);
DISPLAY 0.978723 (-1150 4400);
PAINT WHITE (-1150 4400);
DISPLAY INVISIBLE (-1150 4400);
FORCEPROP 1 LAST PART_NUMBER CS21002FB06
J 0
(-1160 4100);
DISPLAY 0.489362 (-1160 4100);
PAINT SKYBLUE (-1160 4100);
DISPLAY INVISIBLE (-1160 4100);
FORCEADD VCC_CORE..1
(-1200 4550);
FORCEPROP 3 LASTPIN (-1200 4500) SIG_NAME PVDD11_S3_P0\g
J 0
(-1190 4510);
DISPLAY 0.659574 (-1190 4510);
PAINT MONO (-1190 4510);
DISPLAY INVISIBLE (-1190 4510);
FORCEPROP 1 LAST HDL_POWER PVDD11_S3_P0
J 1
(-1200 4600);
DISPLAY 0.489362 (-1200 4600);
PAINT GREEN (-1200 4600);
FORCEPROP 2 LAST CDS_LIB pure_quanta_power
J 0
(-1200 4550);
DISPLAY INVISIBLE (-1200 4550);
FORCEPROP 1 LAST PATH I84
J 0
(-1150 4575);
DISPLAY 0.872340 (-1150 4575);
PAINT AQUA (-1150 4575);
DISPLAY INVISIBLE (-1150 4575);
FORCEADD Q_RES..1
R 1
(-8425 5700);
FORCEPROP 1 LAST LOCATION PR411
J 0
(-8375 5850);
DISPLAY 0.489362 (-8375 5850);
PAINT SKYBLUE (-8375 5850);
FORCEPROP 0 LAST $SEC 1
R 1
J 0
(-8375 5875);
DISPLAY 0.680851 (-8375 5875);
PAINT MONO (-8375 5875);
DISPLAY INVISIBLE (-8375 5875);
FORCEPROP 0 LAST CDS_SEC 1
R 1
J 0
(-8375 5875);
DISPLAY 1.021277 (-8375 5875);
DISPLAY INVISIBLE (-8375 5875);
FORCEPROP 1 LASTPIN (-8425 5600) $PN 1
R 1
J 0
(-8437 5612);
DISPLAY 0.787234 (-8437 5612);
PAINT MONO (-8437 5612);
DISPLAY INVISIBLE (-8437 5612);
FORCEPROP 1 LASTPIN (-8425 5800) $PN 2
R 1
J 0
(-8437 5762);
DISPLAY 0.787234 (-8437 5762);
PAINT MONO (-8437 5762);
DISPLAY INVISIBLE (-8437 5762);
FORCEPROP 1 LAST WATTAGE 1/16W
J 0
(-8375 5700);
DISPLAY 0.489362 (-8375 5700);
PAINT SKYBLUE (-8375 5700);
FORCEPROP 1 LAST MATERIAL CHIP
J 0
(-8375 5650);
DISPLAY 0.489362 (-8375 5650);
PAINT SKYBLUE (-8375 5650);
FORCEPROP 1 LAST TOLERANCE 5%
J 0
(-8375 5750);
DISPLAY 0.489362 (-8375 5750);
PAINT SKYBLUE (-8375 5750);
FORCEPROP 1 LAST VALUE 0
J 2
(-8350 5800);
DISPLAY 0.489362 (-8350 5800);
PAINT SKYBLUE (-8350 5800);
FORCEPROP 1 LAST PACK_TYPE 0402LF
J 0
(-8375 5550);
DISPLAY 0.489362 (-8375 5550);
PAINT SKYBLUE (-8375 5550);
FORCEPROP 2 LAST CDS_LIB pure_quanta
J 0
(-8425 5700);
DISPLAY INVISIBLE (-8425 5700);
FORCEPROP 1 LAST PATH I85
R 1
J 0
(-8575 5650);
DISPLAY 0.978723 (-8575 5650);
PAINT WHITE (-8575 5650);
DISPLAY INVISIBLE (-8575 5650);
FORCEPROP 1 LAST PART_NUMBER CS00002JB13
J 0
(-8375 5600);
DISPLAY 0.489362 (-8375 5600);
PAINT SKYBLUE (-8375 5600);
DISPLAY INVISIBLE (-8375 5600);
FORCEADD Q_RES..1
R 1
(-8075 5700);
FORCEPROP 1 LAST LOCATION PR413
J 0
(-8025 5850);
DISPLAY 0.489362 (-8025 5850);
PAINT SKYBLUE (-8025 5850);
FORCEPROP 0 LAST $SEC 1
R 1
J 0
(-8025 5875);
DISPLAY 0.680851 (-8025 5875);
PAINT MONO (-8025 5875);
DISPLAY INVISIBLE (-8025 5875);
FORCEPROP 0 LAST CDS_SEC 1
R 1
J 0
(-8025 5875);
DISPLAY 1.021277 (-8025 5875);
DISPLAY INVISIBLE (-8025 5875);
FORCEPROP 1 LASTPIN (-8075 5600) $PN 1
R 1
J 0
(-8087 5612);
DISPLAY 0.787234 (-8087 5612);
PAINT MONO (-8087 5612);
DISPLAY INVISIBLE (-8087 5612);
FORCEPROP 1 LASTPIN (-8075 5800) $PN 2
R 1
J 0
(-8087 5762);
DISPLAY 0.787234 (-8087 5762);
PAINT MONO (-8087 5762);
DISPLAY INVISIBLE (-8087 5762);
FORCEPROP 1 LAST VALUE 0
J 2
(-8000 5800);
DISPLAY 0.489362 (-8000 5800);
PAINT SKYBLUE (-8000 5800);
FORCEPROP 1 LAST WATTAGE 1/16W
J 0
(-8025 5700);
DISPLAY 0.489362 (-8025 5700);
PAINT SKYBLUE (-8025 5700);
FORCEPROP 1 LAST MATERIAL EMPTY
J 0
(-8025 5650);
DISPLAY 0.489362 (-8025 5650);
PAINT RED (-8025 5650);
FORCEPROP 1 LAST TOLERANCE 5%
J 0
(-8025 5750);
DISPLAY 0.489362 (-8025 5750);
PAINT SKYBLUE (-8025 5750);
FORCEPROP 1 LAST PACK_TYPE 0402LF
J 0
(-8025 5550);
DISPLAY 0.489362 (-8025 5550);
PAINT SKYBLUE (-8025 5550);
FORCEPROP 2 LAST CDS_LIB pure_quanta
J 0
(-8075 5700);
DISPLAY INVISIBLE (-8075 5700);
FORCEPROP 1 LAST PATH I86
R 1
J 0
(-8225 5650);
DISPLAY 0.978723 (-8225 5650);
PAINT WHITE (-8225 5650);
DISPLAY INVISIBLE (-8225 5650);
FORCEPROP 1 LAST PART_NUMBER CS00002JB13
J 0
(-8025 5600);
DISPLAY 0.489362 (-8025 5600);
PAINT SKYBLUE (-8025 5600);
DISPLAY INVISIBLE (-8025 5600);
FORCEADD Q_CAP..1
(-4200 5325);
FORCEPROP 1 LAST LOCATION PC215_1
J 0
(-4150 5425);
DISPLAY 0.489362 (-4150 5425);
PAINT SKYBLUE (-4150 5425);
FORCEPROP 0 LAST $SEC 1
J 0
(-4150 5450);
DISPLAY 0.680851 (-4150 5450);
PAINT MONO (-4150 5450);
DISPLAY INVISIBLE (-4150 5450);
FORCEPROP 0 LAST CDS_SEC 1
J 0
(-4150 5450);
DISPLAY 1.021277 (-4150 5450);
DISPLAY INVISIBLE (-4150 5450);
FORCEPROP 1 LASTPIN (-4200 5425) $PN 1
J 0
(-4190 5405);
DISPLAY 0.489362 (-4190 5405);
PAINT MONO (-4190 5405);
FORCEPROP 1 LASTPIN (-4200 5225) $PN 2
J 0
(-4190 5205);
DISPLAY 0.489362 (-4190 5205);
PAINT MONO (-4190 5205);
FORCEPROP 1 LAST VOLTAGE 16V
J 0
(-4150 5325);
DISPLAY 0.489362 (-4150 5325);
PAINT SKYBLUE (-4150 5325);
FORCEPROP 1 LAST VALUE 22UF
J 0
(-4150 5375);
DISPLAY 0.489362 (-4150 5375);
PAINT SKYBLUE (-4150 5375);
FORCEPROP 1 LAST PACK_TYPE C0805
J 0
(-4150 5125);
DISPLAY 0.489362 (-4150 5125);
PAINT SKYBLUE (-4150 5125);
FORCEPROP 1 LAST MATERIAL X6S
J 0
(-4150 5225);
DISPLAY 0.489362 (-4150 5225);
PAINT SKYBLUE (-4150 5225);
FORCEPROP 1 LAST TOLERANCE 20%
J 0
(-4150 5275);
DISPLAY 0.489362 (-4150 5275);
PAINT SKYBLUE (-4150 5275);
FORCEPROP 2 LAST CDS_LIB pure_quanta
J 0
(-4200 5325);
DISPLAY INVISIBLE (-4200 5325);
FORCEPROP 1 LAST PATH I87
J 0
(-4150 5475);
DISPLAY 0.978723 (-4150 5475);
PAINT WHITE (-4150 5475);
DISPLAY INVISIBLE (-4150 5475);
FORCEPROP 1 LAST PART_NUMBER CH6223MEA01
J 0
(-4150 5175);
DISPLAY 0.489362 (-4150 5175);
PAINT SKYBLUE (-4150 5175);
DISPLAY INVISIBLE (-4150 5175);
FORCEADD Q_CAP..1
(-4000 5325);
FORCEPROP 1 LAST LOCATION PC219_1
J 0
(-3950 5425);
DISPLAY 0.489362 (-3950 5425);
PAINT SKYBLUE (-3950 5425);
FORCEPROP 0 LAST $SEC 1
J 0
(-3950 5450);
DISPLAY 0.680851 (-3950 5450);
PAINT MONO (-3950 5450);
DISPLAY INVISIBLE (-3950 5450);
FORCEPROP 0 LAST CDS_SEC 1
J 0
(-3950 5450);
DISPLAY 1.021277 (-3950 5450);
DISPLAY INVISIBLE (-3950 5450);
FORCEPROP 1 LASTPIN (-4000 5425) $PN 1
J 0
(-3990 5405);
DISPLAY 0.489362 (-3990 5405);
PAINT MONO (-3990 5405);
FORCEPROP 1 LASTPIN (-4000 5225) $PN 2
J 0
(-3990 5205);
DISPLAY 0.489362 (-3990 5205);
PAINT MONO (-3990 5205);
FORCEPROP 1 LAST VOLTAGE 16V
J 0
(-3950 5325);
DISPLAY 0.489362 (-3950 5325);
PAINT SKYBLUE (-3950 5325);
FORCEPROP 1 LAST VALUE 22UF
J 0
(-3950 5375);
DISPLAY 0.489362 (-3950 5375);
PAINT SKYBLUE (-3950 5375);
FORCEPROP 1 LAST TOLERANCE 20%
J 0
(-3950 5275);
DISPLAY 0.489362 (-3950 5275);
PAINT SKYBLUE (-3950 5275);
FORCEPROP 1 LAST MATERIAL X6S
J 0
(-3950 5225);
DISPLAY 0.489362 (-3950 5225);
PAINT SKYBLUE (-3950 5225);
FORCEPROP 1 LAST PACK_TYPE C0805
J 0
(-3950 5125);
DISPLAY 0.489362 (-3950 5125);
PAINT SKYBLUE (-3950 5125);
FORCEPROP 2 LAST CDS_LIB pure_quanta
J 0
(-4000 5325);
DISPLAY INVISIBLE (-4000 5325);
FORCEPROP 1 LAST PATH I88
J 0
(-3950 5475);
DISPLAY 0.978723 (-3950 5475);
PAINT WHITE (-3950 5475);
DISPLAY INVISIBLE (-3950 5475);
FORCEPROP 1 LAST PART_NUMBER CH6223MEA01
J 0
(-3950 5175);
DISPLAY 0.489362 (-3950 5175);
PAINT SKYBLUE (-3950 5175);
DISPLAY INVISIBLE (-3950 5175);
FORCEADD Q_CAPP..1
(-2075 2850);
FORCEPROP 1 LAST LOCATION PC800
J 0
(-2025 2950);
DISPLAY 0.489362 (-2025 2950);
PAINT SKYBLUE (-2025 2950);
FORCEPROP 0 LAST $SEC 1
J 0
(-2025 2975);
DISPLAY 0.680851 (-2025 2975);
PAINT MONO (-2025 2975);
DISPLAY INVISIBLE (-2025 2975);
FORCEPROP 0 LAST CDS_SEC 1
J 0
(-2025 2975);
DISPLAY 0.680851 (-2025 2975);
DISPLAY INVISIBLE (-2025 2975);
FORCEPROP 1 LASTPIN (-2075 2950) $PN 1
J 0
(-2065 2935);
DISPLAY 0.489362 (-2065 2935);
PAINT MONO (-2065 2935);
FORCEPROP 1 LASTPIN (-2075 2750) $PN 2
J 0
(-2065 2735);
DISPLAY 0.489362 (-2065 2735);
PAINT MONO (-2065 2735);
FORCEPROP 1 LAST MATERIAL SPCAP
J 0
(-2025 2750);
DISPLAY 0.489362 (-2025 2750);
PAINT SKYBLUE (-2025 2750);
FORCEPROP 1 LAST TOLERANCE 20%
J 0
(-2025 2850);
DISPLAY 0.489362 (-2025 2850);
PAINT SKYBLUE (-2025 2850);
FORCEPROP 1 LAST VALUE 470UF
J 0
(-2025 2900);
DISPLAY 0.489362 (-2025 2900);
PAINT SKYBLUE (-2025 2900);
FORCEPROP 1 LAST VOLTAGE 2.5V
J 0
(-2025 2800);
DISPLAY 0.489362 (-2025 2800);
PAINT SKYBLUE (-2025 2800);
FORCEPROP 1 LAST PACK_TYPE SMLF
J 0
(-2025 2700);
DISPLAY 0.489362 (-2025 2700);
PAINT SKYBLUE (-2025 2700);
FORCEPROP 2 LAST CDS_LIB pure_quanta
J 0
(-2075 2850);
DISPLAY INVISIBLE (-2075 2850);
FORCEPROP 1 LAST PATH I89
J 0
(-2025 3000);
DISPLAY 0.978723 (-2025 3000);
DISPLAY INVISIBLE (-2025 3000);
FORCEPROP 1 LAST PART_NUMBER CH747LM8825
J 0
(-2025 2650);
DISPLAY 0.489362 (-2025 2650);
PAINT SKYBLUE (-2025 2650);
DISPLAY INVISIBLE (-2025 2650);
FORCEADD Q_CAP..1
(-7775 1825);
FORCEPROP 1 LAST LOCATION PC204
J 0
(-7725 1925);
DISPLAY 0.489362 (-7725 1925);
PAINT SKYBLUE (-7725 1925);
FORCEPROP 0 LAST $SEC 1
J 0
(-7725 1975);
DISPLAY 0.680851 (-7725 1975);
PAINT MONO (-7725 1975);
DISPLAY INVISIBLE (-7725 1975);
FORCEPROP 0 LAST CDS_SEC 1
J 0
(-7725 1975);
DISPLAY 1.021277 (-7725 1975);
DISPLAY INVISIBLE (-7725 1975);
FORCEPROP 1 LASTPIN (-7775 1925) $PN 1
J 0
(-7765 1905);
DISPLAY 0.489362 (-7765 1905);
PAINT MONO (-7765 1905);
FORCEPROP 1 LASTPIN (-7775 1725) $PN 2
J 0
(-7765 1705);
DISPLAY 0.489362 (-7765 1705);
PAINT MONO (-7765 1705);
FORCEPROP 1 LAST PACK_TYPE C0402
J 0
(-7725 1625);
DISPLAY 0.489362 (-7725 1625);
PAINT SKYBLUE (-7725 1625);
FORCEPROP 1 LAST VOLTAGE 10V
J 0
(-7725 1825);
DISPLAY 0.489362 (-7725 1825);
PAINT SKYBLUE (-7725 1825);
FORCEPROP 1 LAST VALUE 2.2UF
J 0
(-7725 1875);
DISPLAY 0.489362 (-7725 1875);
PAINT SKYBLUE (-7725 1875);
FORCEPROP 1 LAST TOLERANCE 10%
J 0
(-7725 1775);
DISPLAY 0.489362 (-7725 1775);
PAINT SKYBLUE (-7725 1775);
FORCEPROP 1 LAST MATERIAL X6S
J 0
(-7725 1725);
DISPLAY 0.489362 (-7725 1725);
PAINT SKYBLUE (-7725 1725);
FORCEPROP 2 LAST CDS_LIB pure_quanta
J 0
(-7775 1825);
DISPLAY INVISIBLE (-7775 1825);
FORCEPROP 1 LAST PATH I9
J 0
(-7725 1975);
DISPLAY 0.978723 (-7725 1975);
PAINT WHITE (-7725 1975);
DISPLAY INVISIBLE (-7725 1975);
FORCEPROP 1 LAST PART_NUMBER CH5222KEB01
J 0
(-7725 1675);
DISPLAY 0.489362 (-7725 1675);
PAINT SKYBLUE (-7725 1675);
DISPLAY INVISIBLE (-7725 1675);
FORCEADD Q_CAP..1
(-2375 1325);
FORCEPROP 1 LAST LOCATION PC221_2
J 0
(-2325 1425);
DISPLAY 0.489362 (-2325 1425);
PAINT SKYBLUE (-2325 1425);
FORCEPROP 0 LAST $SEC 1
J 0
(-2325 1450);
DISPLAY 0.680851 (-2325 1450);
PAINT MONO (-2325 1450);
DISPLAY INVISIBLE (-2325 1450);
FORCEPROP 0 LAST CDS_SEC 1
J 0
(-2325 1450);
DISPLAY 1.021277 (-2325 1450);
DISPLAY INVISIBLE (-2325 1450);
FORCEPROP 1 LASTPIN (-2375 1425) $PN 1
J 0
(-2365 1405);
DISPLAY 0.489362 (-2365 1405);
PAINT MONO (-2365 1405);
FORCEPROP 1 LASTPIN (-2375 1225) $PN 2
J 0
(-2365 1205);
DISPLAY 0.489362 (-2365 1205);
PAINT MONO (-2365 1205);
FORCEPROP 1 LAST PACK_TYPE C0805
J 0
(-2325 1125);
DISPLAY 0.489362 (-2325 1125);
PAINT SKYBLUE (-2325 1125);
FORCEPROP 1 LAST MATERIAL X6S
J 0
(-2325 1225);
DISPLAY 0.489362 (-2325 1225);
PAINT SKYBLUE (-2325 1225);
FORCEPROP 1 LAST TOLERANCE 20%
J 0
(-2325 1275);
DISPLAY 0.489362 (-2325 1275);
PAINT SKYBLUE (-2325 1275);
FORCEPROP 1 LAST VALUE 22UF
J 0
(-2325 1375);
DISPLAY 0.489362 (-2325 1375);
PAINT SKYBLUE (-2325 1375);
FORCEPROP 1 LAST VOLTAGE 4V
J 0
(-2325 1325);
DISPLAY 0.489362 (-2325 1325);
PAINT SKYBLUE (-2325 1325);
FORCEPROP 2 LAST CDS_LIB pure_quanta
J 0
(-2375 1325);
DISPLAY INVISIBLE (-2375 1325);
FORCEPROP 1 LAST PATH I90
J 0
(-2325 1475);
DISPLAY 0.978723 (-2325 1475);
PAINT WHITE (-2325 1475);
DISPLAY INVISIBLE (-2325 1475);
FORCEPROP 1 LAST PART_NUMBER CH622KMEA03
J 0
(-2325 1175);
DISPLAY 0.489362 (-2325 1175);
PAINT SKYBLUE (-2325 1175);
DISPLAY INVISIBLE (-2325 1175);
FORCEADD Q_RES..1
(-3450 550);
FORCEPROP 1 LAST LOCATION PR138
J 0
(-3500 600);
DISPLAY 0.489362 (-3500 600);
PAINT SKYBLUE (-3500 600);
FORCEPROP 0 LAST $SEC 1
J 0
(-3500 650);
DISPLAY 0.680851 (-3500 650);
PAINT MONO (-3500 650);
DISPLAY INVISIBLE (-3500 650);
FORCEPROP 0 LAST CDS_SEC 1
J 0
(-3500 650);
DISPLAY 1.021277 (-3500 650);
DISPLAY INVISIBLE (-3500 650);
FORCEPROP 1 LASTPIN (-3550 550) $PN 1
J 0
(-3538 562);
DISPLAY 0.489362 (-3538 562);
PAINT MONO (-3538 562);
FORCEPROP 1 LASTPIN (-3350 550) $PN 2
J 0
(-3388 562);
DISPLAY 0.489362 (-3388 562);
PAINT MONO (-3388 562);
FORCEPROP 1 LAST PACK_TYPE 0402LF
J 0
(-3350 475);
DISPLAY 0.489362 (-3350 475);
PAINT SKYBLUE (-3350 475);
FORCEPROP 1 LAST WATTAGE 1/16W
J 0
(-3350 500);
DISPLAY 0.489362 (-3350 500);
PAINT SKYBLUE (-3350 500);
FORCEPROP 1 LAST MATERIAL CHIP
J 0
(-3700 475);
DISPLAY 0.489362 (-3700 475);
PAINT SKYBLUE (-3700 475);
FORCEPROP 1 LAST TOLERANCE 5%
J 0
(-3325 575);
DISPLAY 0.489362 (-3325 575);
PAINT SKYBLUE (-3325 575);
FORCEPROP 1 LAST VALUE 0
J 2
(-3575 575);
DISPLAY 0.489362 (-3575 575);
PAINT SKYBLUE (-3575 575);
FORCEPROP 2 LAST CDS_LIB pure_quanta
J 0
(-3450 550);
DISPLAY INVISIBLE (-3450 550);
FORCEPROP 1 LAST PATH I91
J 0
(-3500 700);
DISPLAY 0.978723 (-3500 700);
PAINT WHITE (-3500 700);
DISPLAY INVISIBLE (-3500 700);
FORCEPROP 1 LAST PART_NUMBER CS00002JB13
J 0
(-3700 500);
DISPLAY 0.489362 (-3700 500);
PAINT SKYBLUE (-3700 500);
DISPLAY INVISIBLE (-3700 500);
FORCEADD ISL99390FRZTR5935..1
(-6050 4425);
FORCEPROP 1 LAST LOCATION PU22
J 0
(-6350 5300);
DISPLAY 0.489362 (-6350 5300);
PAINT SKYBLUE (-6350 5300);
FORCEPROP 0 LAST $SEC 1
J 0
(-6350 5450);
DISPLAY 0.680851 (-6350 5450);
PAINT MONO (-6350 5450);
DISPLAY INVISIBLE (-6350 5450);
FORCEPROP 2 LAST CDS_SEC 1
J 0
(-6350 5450);
DISPLAY 1.021277 (-6350 5450);
DISPLAY INVISIBLE (-6350 5450);
FORCEPROP 0 LASTPIN (-5650 3975) $PN 2
J 0
(-5640 3985);
DISPLAY 0.489362 (-5640 3985);
PAINT MONO (-5640 3985);
FORCEPROP 0 LASTPIN (-5650 4775) $PN 33
J 0
(-5640 4785);
DISPLAY 0.489362 (-5640 4785);
PAINT MONO (-5640 4785);
FORCEPROP 0 LASTPIN (-6500 4175) $PN 31
J 2
(-6510 4185);
DISPLAY 0.489362 (-6510 4185);
PAINT MONO (-6510 4185);
FORCEPROP 0 LASTPIN (-6500 4575) $PN 35
J 2
(-6510 4585);
DISPLAY 0.489362 (-6510 4585);
PAINT MONO (-6510 4585);
FORCEPROP 0 LASTPIN (-5650 4125) $PN 6
J 0
(-5640 4135);
DISPLAY 0.489362 (-5640 4135);
PAINT MONO (-5640 4135);
FORCEPROP 0 LASTPIN (-5650 4075) $PN 41
J 0
(-5640 4085);
DISPLAY 0.489362 (-5640 4085);
PAINT MONO (-5640 4085);
FORCEPROP 0 LASTPIN (-6500 4425) $PN 38
J 2
(-6510 4435);
DISPLAY 0.489362 (-6510 4435);
PAINT MONO (-6510 4435);
FORCEPROP 0 LASTPIN (-6500 4125) $PN 37
J 2
(-6510 4135);
DISPLAY 0.489362 (-6510 4135);
PAINT MONO (-6510 4135);
FORCEPROP 0 LASTPIN (-5650 3925) $PN 5
J 0
(-5640 3935);
DISPLAY 0.489362 (-5640 3935);
PAINT MONO (-5640 3935);
FORCEPROP 0 LASTPIN (-5650 3875) $PN 7_9-20_24
J 0
(-5640 3885);
DISPLAY 0.489362 (-5640 3885);
PAINT MONO (-5640 3885);
FORCEPROP 0 LASTPIN (-5650 3825) $PN 40
J 0
(-5640 3835);
DISPLAY 0.489362 (-5640 3835);
PAINT MONO (-5640 3835);
FORCEPROP 0 LASTPIN (-5650 4525) $PN 32
J 0
(-5640 4535);
DISPLAY 0.489362 (-5640 4535);
PAINT MONO (-5640 4535);
FORCEPROP 0 LASTPIN (-6500 5075) $PN 4
J 2
(-6510 5085);
DISPLAY 0.489362 (-6510 5085);
PAINT MONO (-6510 5085);
FORCEPROP 0 LASTPIN (-6500 3825) $PN 34
J 2
(-6510 3835);
DISPLAY 0.489362 (-6510 3835);
PAINT MONO (-6510 3835);
FORCEPROP 0 LASTPIN (-6500 4325) $PN 39
J 2
(-6510 4335);
DISPLAY 0.489362 (-6510 4335);
PAINT MONO (-6510 4335);
FORCEPROP 0 LASTPIN (-5650 4425) $PN 10_19
J 0
(-5640 4435);
DISPLAY 0.489362 (-5640 4435);
PAINT MONO (-5640 4435);
FORCEPROP 0 LASTPIN (-6500 3925) $PN 36
J 2
(-6510 3935);
DISPLAY 0.489362 (-6510 3935);
PAINT MONO (-6510 3935);
FORCEPROP 0 LASTPIN (-6500 4775) $PN 3
J 2
(-6510 4785);
DISPLAY 0.489362 (-6510 4785);
PAINT MONO (-6510 4785);
FORCEPROP 0 LASTPIN (-5650 5075) $PN 25_29
J 0
(-5640 5085);
DISPLAY 0.489362 (-5640 5085);
PAINT MONO (-5640 5085);
FORCEPROP 0 LASTPIN (-5650 5025) $PN 30
J 0
(-5640 5035);
DISPLAY 0.489362 (-5640 5035);
PAINT MONO (-5640 5035);
FORCEPROP 0 LASTPIN (-5650 4175) $PN 1
J 0
(-5640 4185);
DISPLAY 0.489362 (-5640 4185);
PAINT MONO (-5640 4185);
FORCEPROP 1 LAST MATERIAL IC
J 0
(-6350 5150);
DISPLAY 0.489362 (-6350 5150);
PAINT SKYBLUE (-6350 5150);
FORCEPROP 2 LAST VALUE ISL99390FRZ-TR5935
J 0
(-6350 5350);
DISPLAY 0.489362 (-6350 5350);
PAINT SKYBLUE (-6350 5350);
FORCEPROP 2 LAST PART_TYPE SMLF
J 0
(-6350 5400);
DISPLAY 1.021277 (-6350 5400);
FORCEPROP 2 LAST CDS_LIB pure_quanta
J 0
(-6050 4425);
DISPLAY INVISIBLE (-6050 4425);
FORCEPROP 1 LAST NEEDS_NO_SIZE TRUE
J 0
(-6050 4425);
DISPLAY 0.723404 (-6050 4425);
PAINT GREEN (-6050 4425);
DISPLAY INVISIBLE (-6050 4425);
FORCEPROP 1 LAST CDS_LMAN_SYM_OUTLINE -300,700,250,-650
J 0
(-6050 4425);
DISPLAY 0.468085 (-6050 4425);
PAINT GREEN (-6050 4425);
DISPLAY INVISIBLE (-6050 4425);
FORCEPROP 1 LAST PATH I92
J 0
(-6050 4425);
DISPLAY 0.723404 (-6050 4425);
PAINT GREEN (-6050 4425);
DISPLAY INVISIBLE (-6050 4425);
FORCEPROP 1 LAST PART_NUMBER AL099390004
J 0
(-6350 5225);
DISPLAY 0.489362 (-6350 5225);
PAINT SKYBLUE (-6350 5225);
DISPLAY INVISIBLE (-6350 5225);
FORCEADD Q_CAP..1
(-3800 5325);
FORCEPROP 1 LAST LOCATION PC8004
J 0
(-3750 5425);
DISPLAY 0.489362 (-3750 5425);
PAINT SKYBLUE (-3750 5425);
FORCEPROP 0 LAST $SEC 1
J 0
(-3750 5450);
DISPLAY 0.680851 (-3750 5450);
PAINT MONO (-3750 5450);
DISPLAY INVISIBLE (-3750 5450);
FORCEPROP 0 LAST CDS_SEC 1
J 0
(-3750 5450);
DISPLAY 0.680851 (-3750 5450);
DISPLAY INVISIBLE (-3750 5450);
FORCEPROP 1 LASTPIN (-3800 5425) $PN 1
J 0
(-3790 5405);
DISPLAY 0.787234 (-3790 5405);
PAINT MONO (-3790 5405);
FORCEPROP 1 LASTPIN (-3800 5225) $PN 2
J 0
(-3790 5205);
DISPLAY 0.787234 (-3790 5205);
PAINT MONO (-3790 5205);
FORCEPROP 1 LAST VOLTAGE 16V
J 0
(-3750 5325);
DISPLAY 0.489362 (-3750 5325);
PAINT SKYBLUE (-3750 5325);
FORCEPROP 1 LAST TOLERANCE 20%
J 0
(-3750 5275);
DISPLAY 0.489362 (-3750 5275);
PAINT SKYBLUE (-3750 5275);
FORCEPROP 1 LAST MATERIAL X6S
J 0
(-3750 5225);
DISPLAY 0.489362 (-3750 5225);
PAINT SKYBLUE (-3750 5225);
FORCEPROP 1 LAST PACK_TYPE C0805
J 0
(-3750 5125);
DISPLAY 0.489362 (-3750 5125);
PAINT SKYBLUE (-3750 5125);
FORCEPROP 1 LAST VALUE 22UF
J 0
(-3750 5375);
DISPLAY 0.489362 (-3750 5375);
PAINT SKYBLUE (-3750 5375);
FORCEPROP 2 LAST CDS_LIB pure_quanta
J 0
(-3800 5325);
DISPLAY INVISIBLE (-3800 5325);
FORCEPROP 1 LAST PATH I93
J 0
(-3750 5475);
DISPLAY 0.978723 (-3750 5475);
PAINT WHITE (-3750 5475);
DISPLAY INVISIBLE (-3750 5475);
FORCEPROP 1 LAST PART_NUMBER CH6223MEA01
J 0
(-3750 5175);
DISPLAY 0.297872 (-3750 5175);
PAINT SKYBLUE (-3750 5175);
DISPLAY INVISIBLE (-3750 5175);
FORCEADD Q_CAP..1
(-3375 2400);
FORCEPROP 1 LAST LOCATION PC8005
J 0
(-3325 2500);
DISPLAY 0.489362 (-3325 2500);
PAINT SKYBLUE (-3325 2500);
FORCEPROP 0 LAST $SEC 1
J 0
(-3325 2525);
DISPLAY 0.680851 (-3325 2525);
PAINT MONO (-3325 2525);
DISPLAY INVISIBLE (-3325 2525);
FORCEPROP 0 LAST CDS_SEC 1
J 0
(-3325 2525);
DISPLAY 0.680851 (-3325 2525);
DISPLAY INVISIBLE (-3325 2525);
FORCEPROP 1 LASTPIN (-3375 2500) $PN 1
J 0
(-3365 2480);
DISPLAY 0.787234 (-3365 2480);
PAINT MONO (-3365 2480);
FORCEPROP 1 LASTPIN (-3375 2300) $PN 2
J 0
(-3365 2280);
DISPLAY 0.787234 (-3365 2280);
PAINT MONO (-3365 2280);
FORCEPROP 1 LAST VOLTAGE 16V
J 0
(-3325 2400);
DISPLAY 0.489362 (-3325 2400);
PAINT SKYBLUE (-3325 2400);
FORCEPROP 1 LAST TOLERANCE 20%
J 0
(-3325 2350);
DISPLAY 0.489362 (-3325 2350);
PAINT SKYBLUE (-3325 2350);
FORCEPROP 1 LAST MATERIAL X6S
J 0
(-3325 2300);
DISPLAY 0.489362 (-3325 2300);
PAINT SKYBLUE (-3325 2300);
FORCEPROP 1 LAST VALUE 22UF
J 0
(-3325 2450);
DISPLAY 0.489362 (-3325 2450);
PAINT SKYBLUE (-3325 2450);
FORCEPROP 1 LAST PACK_TYPE C0805
J 0
(-3325 2200);
DISPLAY 0.489362 (-3325 2200);
PAINT SKYBLUE (-3325 2200);
FORCEPROP 2 LAST CDS_LIB pure_quanta
J 0
(-3375 2400);
DISPLAY INVISIBLE (-3375 2400);
FORCEPROP 1 LAST PATH I94
J 0
(-3325 2550);
DISPLAY 0.978723 (-3325 2550);
PAINT WHITE (-3325 2550);
DISPLAY INVISIBLE (-3325 2550);
FORCEPROP 1 LAST PART_NUMBER CH6223MEA01
J 0
(-3325 2250);
DISPLAY 0.489362 (-3325 2250);
PAINT SKYBLUE (-3325 2250);
DISPLAY INVISIBLE (-3325 2250);
FORCEADD Q_CAP..1
(-3550 5325);
FORCEPROP 1 LAST LOCATION PC7002
J 0
(-3500 5425);
DISPLAY 0.787234 (-3500 5425);
FORCEPROP 0 LAST $SEC 1
J 0
(-3500 5475);
DISPLAY 0.680851 (-3500 5475);
PAINT MONO (-3500 5475);
DISPLAY INVISIBLE (-3500 5475);
FORCEPROP 0 LAST CDS_SEC 1
J 0
(-3500 5475);
DISPLAY 0.680851 (-3500 5475);
DISPLAY INVISIBLE (-3500 5475);
FORCEPROP 1 LASTPIN (-3550 5425) $PN 1
J 0
(-3540 5405);
DISPLAY 0.787234 (-3540 5405);
PAINT MONO (-3540 5405);
FORCEPROP 1 LASTPIN (-3550 5225) $PN 2
J 0
(-3540 5205);
DISPLAY 0.787234 (-3540 5205);
PAINT MONO (-3540 5205);
FORCEPROP 1 LAST MATERIAL X6S
J 0
(-3500 5225);
DISPLAY 0.510638 (-3500 5225);
FORCEPROP 1 LAST PACK_TYPE C0805
J 0
(-3500 5125);
DISPLAY 0.510638 (-3500 5125);
FORCEPROP 1 LAST TOLERANCE 20%
J 0
(-3500 5275);
DISPLAY 0.510638 (-3500 5275);
FORCEPROP 1 LAST VOLTAGE 16V
J 0
(-3500 5325);
DISPLAY 0.510638 (-3500 5325);
FORCEPROP 1 LAST VALUE 22UF
J 0
(-3500 5375);
DISPLAY 0.510638 (-3500 5375);
FORCEPROP 2 LAST CDS_LIB pure_quanta
J 0
(-3550 5325);
DISPLAY INVISIBLE (-3550 5325);
FORCEPROP 1 LAST PATH I95
J 0
(-3500 5475);
DISPLAY 0.978723 (-3500 5475);
PAINT WHITE (-3500 5475);
DISPLAY INVISIBLE (-3500 5475);
FORCEPROP 1 LAST PART_NUMBER CH6223MEA01
J 0
(-3500 5175);
DISPLAY 0.404255 (-3500 5175);
DISPLAY INVISIBLE (-3500 5175);
FORCEADD DNS..1
(-4575 825);
PAINT RED (-4575 825);
FORCEPROP 2 LAST CDS_LIB mstr_misc
J 0
(-4575 825);
DISPLAY INVISIBLE (-4575 825);
FORCEPROP 1 LAST COMMENT_BODY TRUE
R 1
J 0
(-4500 600);
DISPLAY 0.872340 (-4500 600);
PAINT GREEN (-4500 600);
DISPLAY INVISIBLE (-4500 600);
FORCEADD DNS..1
(-7200 4100);
PAINT RED (-7200 4100);
FORCEPROP 2 LAST CDS_LIB mstr_misc
J 0
(-7200 4100);
DISPLAY INVISIBLE (-7200 4100);
FORCEPROP 1 LAST COMMENT_BODY TRUE
R 1
J 0
(-7125 3875);
DISPLAY 0.872340 (-7125 3875);
PAINT GREEN (-7125 3875);
DISPLAY INVISIBLE (-7125 3875);
FORCEADD DNS..1
(-7200 1200);
PAINT RED (-7200 1200);
FORCEPROP 2 LAST CDS_LIB mstr_misc
J 0
(-7200 1200);
DISPLAY INVISIBLE (-7200 1200);
FORCEPROP 1 LAST COMMENT_BODY TRUE
R 1
J 0
(-7125 975);
DISPLAY 0.872340 (-7125 975);
PAINT GREEN (-7125 975);
DISPLAY INVISIBLE (-7125 975);
FORCEADD DNS..1
(-8050 5700);
PAINT RED (-8050 5700);
FORCEPROP 2 LAST CDS_LIB mstr_misc
J 0
(-8050 5700);
DISPLAY INVISIBLE (-8050 5700);
FORCEPROP 1 LAST COMMENT_BODY TRUE
R 1
J 0
(-7975 5475);
DISPLAY 0.872340 (-7975 5475);
PAINT GREEN (-7975 5475);
DISPLAY INVISIBLE (-7975 5475);
FORCEADD DNS..1
(-4675 3750);
PAINT RED (-4675 3750);
FORCEPROP 2 LAST CDS_LIB mstr_misc
J 0
(-4675 3750);
DISPLAY INVISIBLE (-4675 3750);
FORCEPROP 1 LAST COMMENT_BODY TRUE
R 1
J 0
(-4600 3525);
DISPLAY 0.872340 (-4600 3525);
PAINT GREEN (-4600 3525);
DISPLAY INVISIBLE (-4600 3525);
FORCEADD DNS..1
(-4675 4225);
PAINT RED (-4675 4225);
FORCEPROP 2 LAST CDS_LIB mstr_misc
J 0
(-4675 4225);
DISPLAY INVISIBLE (-4675 4225);
FORCEPROP 1 LAST COMMENT_BODY TRUE
R 1
J 0
(-4600 4000);
DISPLAY 0.872340 (-4600 4000);
PAINT GREEN (-4600 4000);
DISPLAY INVISIBLE (-4600 4000);
FORCEADD QUANTA_TITLE_BLOCK_C..1
(-100 -475);
FORCEPROP 0 LAST CDS_CON_LAST_MODIFIED Thu Sep 14 16:12:20 2023
J 0
(-1985 -460);
DISPLAY INVISIBLE (-1985 -460);
FORCEPROP 1 LAST CUSTOM_TXT_CDS <CON_LAST_MODIFIED>
J 0
(-1985 -460);
DISPLAY 0.978723 (-1985 -460);
FORCEPROP 2 LAST CUSTOM_TXT_CDS <XR_PAGE_TITLE>
J 0
(-7990 4775);
DISPLAY 0.638298 (-7990 4775);
PAINT PINK (-7990 4775);
DISPLAY INVISIBLE (-7990 4775);
FORCEPROP 1 LAST CUSTOM_TXT_CDS <NAME_2>
J 0
(-3275 -425);
FORCEPROP 1 LAST CUSTOM_TXT_CDS <NAME_1>
J 0
(-3275 -300);
FORCEPROP 1 LAST CUSTOM_TXT_CDS <Q_NUMBER>
J 0
(-1503 -372);
DISPLAY 1.212766 (-1503 -372);
FORCEPROP 1 LAST CUSTOM_TXT_CDS <Q_PROJ>
J 0
(-2482 -373);
DISPLAY 1.212766 (-2482 -373);
FORCEPROP 1 LAST CUSTOM_TXT_CDS <Q_REV>
J 0
(-284 -372);
DISPLAY 1.212766 (-284 -372);
FORCEPROP 1 LAST CUSTOM_TXT_CDS <CON_PAGE_NUM> OF <CON_TOTAL_PAGES>
J 0
(-546 -457);
DISPLAY 0.978723 (-546 -457);
FORCEPROP 1 LAST Q_TITLE PVDD11_S3_P0 VR PHASE 1&2
J 0
(-9400 -425);
DISPLAY 2.446809 (-9400 -425);
PAINT GREEN (-9400 -425);
FORCEPROP 1 LAST CDS_LMAN_SYM_OUTLINE -9475,6775,100,-125
J 0
(-100 -475);
DISPLAY 0.468085 (-100 -475);
PAINT GREEN (-100 -475);
DISPLAY INVISIBLE (-100 -475);
FORCEPROP 2 LAST CDS_LIB pure_quanta
J 0
(-100 -475);
DISPLAY INVISIBLE (-100 -475);
FORCEPROP 2 LAST PAGE_BORDER TRUE
J 0
(-7990 4775);
DISPLAY 0.638298 (-7990 4775);
PAINT PINK (-7990 4775);
DISPLAY INVISIBLE (-7990 4775);
FORCEPROP 2 LAST CDS_XR_PAGE_TITLE CR-208 : @T6G_MB_LIB.T6G(SCH_1):PAGE208
J 0
(-7990 4775);
DISPLAY 0.638298 (-7990 4775);
PAINT PINK (-7990 4775);
DISPLAY INVISIBLE (-7990 4775);
FORCEPROP 1 LAST Q_DEPT BU9
J 1
(-3863 -426);
DISPLAY 1.957447 (-3863 -426);
PAINT GREEN (-3863 -426);
DISPLAY INVISIBLE (-3863 -426);
FORCEPROP 1 LAST COMMENT_BODY TRUE
J 0
(-88 -488);
DISPLAY 0.978723 (-88 -488);
PAINT GREEN (-88 -488);
DISPLAY INVISIBLE (-88 -488);
FORCEADD DNS..1
(-4575 1300);
PAINT RED (-4575 1300);
FORCEPROP 2 LAST CDS_LIB mstr_misc
J 0
(-4575 1300);
DISPLAY INVISIBLE (-4575 1300);
FORCEPROP 1 LAST COMMENT_BODY TRUE
R 1
J 0
(-4500 1075);
DISPLAY 0.872340 (-4500 1075);
PAINT GREEN (-4500 1075);
DISPLAY INVISIBLE (-4500 1075);
WIRE 16 -1 (-7275 1200)(-7500 1200);
WIRE 16 -1 (-7500 1200)(-7500 1075);
WIRE 16 -1 (-7425 2300)(-7425 2175);
WIRE 16 -1 (-7875 4050)(-7875 3925);
WIRE 16 -1 (-7300 4125)(-7525 4125);
WIRE 16 -1 (-7525 4125)(-7525 4000);
WIRE 16 -1 (-4550 725)(-4550 650);
WIRE 16 -1 (-8425 5850)(-8425 5800);
WIRE 16 -1 (-4650 3650)(-4650 3575);
WIRE 16 -1 (-7775 4650)(-7775 4600);
WIRE 16 -1 (-7425 5225)(-7425 5100);
WIRE 16 -1 (-7825 1125)(-7825 1000);
WIRE 16 -1 (-8075 5850)(-8075 5800);
WIRE 16 -1 (-2275 5200)(-2275 5025);
WIRE 16 -1 (-7775 1725)(-7775 1675);
WIRE 16 -1 (-6500 3925)(-7125 3925);
FORCEPROP 2 LAST SIG_NAME PVDD11_S3_P0_TEMP0
J 2
(-6585 3935);
DISPLAY 0.489362 (-6585 3935);
WIRE 16 -1 (-7000 4900)(-7000 4775);
FORCEPROP 2 LAST SIG_NAME PVDD11_S3_P0_VCC1
J 2
(-6585 4785);
DISPLAY 0.489362 (-6585 4785);
FORCEPROP 2 LASTPROP $XRERR UNIQUE?
J 0
(-6825 4785);
DISPLAY 0.638298 (-6825 4785);
PAINT MONO (-6825 4785);
DISPLAY INVISIBLE (-6825 4785);
WIRE 16 -1 (-7000 4900)(-7775 4900);
WIRE 16 -1 (-6500 4775)(-7000 4775);
WIRE 16 -1 (-7000 4775)(-7000 4575);
WIRE 16 -1 (-7000 4575)(-6500 4575);
WIRE 16 -1 (-7775 5200)(-7775 4900);
WIRE 16 -1 (-7775 4900)(-7775 4850);
WIRE 16 -1 (-5650 4425)(-4650 4425);
FORCEPROP 2 LAST SIG_NAME SW_PVDD11_S3_P0_SW1
J 0
(-5510 4435);
DISPLAY 0.489362 (-5510 4435);
FORCEPROP 2 LASTPROP $XRERR UNIQUE?
J 0
(-5750 4435);
DISPLAY 0.638298 (-5750 4435);
PAINT MONO (-5750 4435);
DISPLAY INVISIBLE (-5750 4435);
WIRE 16 -1 (-4650 4425)(-3375 4425);
WIRE 16 -1 (-4650 4325)(-4650 4425);
WIRE 16 -1 (-5425 3975)(-5425 3925);
WIRE 16 -1 (-5425 3975)(-5650 3975);
WIRE 16 -1 (-5425 3925)(-5425 3875);
WIRE 16 -1 (-5650 3925)(-5425 3925);
WIRE 16 -1 (-5425 3825)(-5425 3875);
WIRE 16 -1 (-5650 3875)(-5425 3875);
WIRE 16 -1 (-5425 3750)(-5425 3825);
WIRE 16 -1 (-5650 3825)(-5425 3825);
WIRE 16 -1 (-6500 3825)(-7100 3825);
FORCEPROP 2 LAST SIG_NAME PVDD11_S3_P0_PWM1
J 2
(-6585 3835);
DISPLAY 0.489362 (-6585 3835);
WIRE 16 -1 (-7075 1200)(-6450 1200);
FORCEPROP 2 LAST SIG_NAME PVDD11_S3_P0_LSET2
J 2
(-6535 1210);
DISPLAY 0.489362 (-6535 1210);
FORCEPROP 2 LASTPROP $XRERR UNIQUE?
J 0
(-6775 1210);
DISPLAY 0.638298 (-6775 1210);
PAINT MONO (-6775 1210);
DISPLAY INVISIBLE (-6775 1210);
WIRE 16 -1 (-5650 4075)(-5125 4075);
FORCEPROP 2 LAST SIG_NAME NC_PVDD11_S3_P0_GL2_1
J 0
(-5510 4085);
DISPLAY 0.489362 (-5510 4085);
FORCEPROP 2 LASTPROP $XRERR UNIQUE?
J 0
(-5095 4075);
DISPLAY 0.638298 (-5095 4075);
PAINT MONO (-5095 4075);
DISPLAY INVISIBLE (-5095 4075);
WIRE 16 -1 (-3925 4550)(-3925 4525);
WIRE 16 -1 (-3925 4525)(-5650 4525);
FORCEPROP 2 LAST SIG_NAME SW_PVDD11_S3_P0_PH1
J 0
(-5510 4535);
DISPLAY 0.489362 (-5510 4535);
FORCEPROP 2 LASTPROP $XRERR UNIQUE?
J 0
(-5750 4535);
DISPLAY 0.638298 (-5750 4535);
PAINT MONO (-5750 4535);
DISPLAY INVISIBLE (-5750 4535);
WIRE 16 -1 (-2275 5650)(-2275 5500);
WIRE 16 -1 (-2275 5500)(-2275 5400);
WIRE 16 -1 (-2275 5500)(-2800 5500);
WIRE 16 -1 (-5375 5225)(-5375 5100);
WIRE 16 -1 (-5375 5100)(-5050 5100);
WIRE 16 -1 (-5050 5225)(-5050 5100);
WIRE 16 -1 (-5050 5100)(-4750 5100);
WIRE 16 -1 (-4750 5225)(-4750 5100);
WIRE 16 -1 (-4425 5100)(-4750 5100);
WIRE 16 -1 (-4425 5225)(-4425 5100);
WIRE 16 -1 (-4200 5100)(-4425 5100);
WIRE 16 -1 (-4000 5100)(-4200 5100);
WIRE 16 -1 (-4200 5225)(-4200 5100);
WIRE 16 -1 (-4000 5225)(-4000 5100);
WIRE 16 -1 (-4000 5100)(-3900 5100);
WIRE 16 -1 (-3800 5100)(-3900 5100);
WIRE 16 -1 (-3900 5100)(-3900 5050);
WIRE 16 -1 (-3800 5225)(-3800 5100);
WIRE 16 -1 (-3550 5100)(-3800 5100);
WIRE 16 -1 (-3550 5225)(-3550 5100);
WIRE 16 -1 (-3250 5100)(-3550 5100);
WIRE 16 -1 (-3250 5225)(-3250 5100);
WIRE 16 -1 (-6825 2150)(-6450 2150);
WIRE 16 -1 (-6825 2150)(-6825 2600);
WIRE 16 -1 (-6825 2600)(-7425 2600);
WIRE 16 -1 (-7425 2500)(-7425 2600);
WIRE 16 -1 (-7425 2600)(-7775 2600);
WIRE 16 -1 (-7775 2750)(-7775 2600);
WIRE 16 -1 (-7775 2475)(-7775 2600);
WIRE 16 -1 (-5425 1050)(-5600 1050);
WIRE 16 -1 (-5425 1050)(-5425 1000);
WIRE 16 -1 (-5425 950)(-5425 1000);
WIRE 16 -1 (-5600 1000)(-5425 1000);
WIRE 16 -1 (-5425 900)(-5425 950);
WIRE 16 -1 (-5600 950)(-5425 950);
WIRE 16 -1 (-5425 825)(-5425 900);
WIRE 16 -1 (-5600 900)(-5425 900);
WIRE 16 -1 (-6850 5075)(-6850 5525);
WIRE 16 -1 (-6850 5075)(-6500 5075);
WIRE 16 -1 (-6850 5525)(-7425 5525);
WIRE 16 -1 (-7425 5425)(-7425 5525);
WIRE 16 -1 (-7575 5525)(-7425 5525);
WIRE 16 -1 (-7575 5850)(-7575 5525);
WIRE 16 -1 (-7575 5525)(-7775 5525);
WIRE 16 -1 (-7775 5400)(-7775 5525);
WIRE 16 -1 (-7775 5525)(-8075 5525);
WIRE 16 -1 (-8075 5600)(-8075 5525);
WIRE 16 -1 (-8075 5525)(-8425 5525);
WIRE 16 -1 (-8425 5600)(-8425 5525);
WIRE 16 -1 (-5325 2300)(-5325 2175);
WIRE 16 -1 (-5325 2175)(-5000 2175);
WIRE 16 -1 (-5000 2175)(-4675 2175);
WIRE 16 -1 (-5000 2300)(-5000 2175);
WIRE 16 -1 (-4675 2175)(-4375 2175);
WIRE 16 -1 (-4675 2300)(-4675 2175);
WIRE 16 -1 (-4050 2175)(-4375 2175);
WIRE 16 -1 (-4375 2300)(-4375 2175);
WIRE 16 -1 (-3700 2175)(-4050 2175);
WIRE 16 -1 (-4050 2300)(-4050 2175);
WIRE 16 -1 (-3375 2175)(-3700 2175);
WIRE 16 -1 (-3700 2300)(-3700 2175);
WIRE 16 -1 (-3700 2175)(-3700 2125);
WIRE 16 -1 (-3375 2300)(-3375 2175);
WIRE 16 -1 (-5475 2575)(-5475 2150);
WIRE 16 -1 (-5475 2575)(-5325 2575);
WIRE 16 -1 (-5475 2150)(-5475 2100);
WIRE 16 -1 (-5600 2150)(-5475 2150);
WIRE 16 -1 (-5475 2100)(-5600 2100);
WIRE 16 -1 (-5000 2575)(-5325 2575);
WIRE 16 -1 (-5325 2500)(-5325 2575);
WIRE 16 -1 (-4675 2575)(-5000 2575);
WIRE 16 -1 (-5000 2500)(-5000 2575);
WIRE 16 -1 (-4675 2575)(-4375 2575);
WIRE 16 -1 (-4675 2575)(-4675 2500);
WIRE 16 -1 (-4050 2575)(-4375 2575);
WIRE 16 -1 (-4375 2575)(-4375 2500);
WIRE 16 -1 (-3700 2575)(-4050 2575);
WIRE 16 -1 (-4050 2500)(-4050 2575);
WIRE 16 -1 (-3700 2575)(-3375 2575);
WIRE 16 -1 (-3700 2625)(-3700 2575);
WIRE 16 -1 (-3700 2500)(-3700 2575);
WIRE 16 -1 (-3375 2575)(-3375 2500);
WIRE 16 -1 (-2075 2625)(-2400 2625);
WIRE 16 -1 (-2075 2750)(-2075 2625);
WIRE 16 -1 (-2400 2750)(-2400 2625);
WIRE 16 -1 (-2400 2625)(-2725 2625);
WIRE 16 -1 (-2725 2625)(-2725 2750);
WIRE 16 -1 (-2725 2575)(-2725 2625);
WIRE 16 -1 (-2400 3025)(-2075 3025);
WIRE 16 -1 (-2400 2950)(-2400 3025);
WIRE 16 -1 (-2400 3025)(-2725 3025);
WIRE 16 -1 (-2075 3025)(-2075 2950);
WIRE 16 -1 (-2725 2950)(-2725 3025);
WIRE 16 -1 (-2725 3025)(-2725 3050);
WIRE 16 -1 (-2375 1225)(-2375 1100);
WIRE 16 -1 (-1950 1100)(-2375 1100);
WIRE 16 -1 (-1950 1225)(-1950 1100);
WIRE 16 -1 (-1950 1025)(-1950 1100);
WIRE 16 -1 (-2625 1500)(-2375 1500);
WIRE 16 -1 (-2625 1500)(-2625 550);
WIRE 16 -1 (-2625 1500)(-3275 1500);
WIRE 16 -1 (-2375 1500)(-1950 1500);
WIRE 16 -1 (-2375 1500)(-2375 1425);
WIRE 16 -1 (-1950 1600)(-1950 1500);
WIRE 16 -1 (-1950 1500)(-1950 1425);
WIRE 16 -1 (-2625 550)(-3350 550);
WIRE 16 -1 (-700 2650)(-1050 2650);
WIRE 16 -1 (-700 2775)(-700 2650);
WIRE 16 -1 (-1050 2775)(-1050 2650);
WIRE 16 -1 (-1050 2650)(-1350 2650);
WIRE 16 -1 (-1350 2775)(-1350 2650);
WIRE 16 -1 (-1675 2650)(-1350 2650);
WIRE 16 -1 (-1675 2775)(-1675 2650);
WIRE 16 -1 (-1675 2650)(-1675 2600);
WIRE 16 -1 (-1350 3025)(-1050 3025);
WIRE 16 -1 (-1350 2975)(-1350 3025);
WIRE 16 -1 (-1675 3025)(-1350 3025);
WIRE 16 -1 (-1050 3025)(-700 3025);
WIRE 16 -1 (-1050 3025)(-1050 2975);
WIRE 16 -1 (-700 3025)(-700 2975);
WIRE 16 -1 (-1675 2975)(-1675 3025);
WIRE 16 -1 (-1675 3025)(-1675 3050);
WIRE 16 -1 (-2300 4025)(-2300 4150);
WIRE 16 -1 (-2300 4025)(-1950 4025);
WIRE 16 -1 (-1950 4150)(-1950 4025);
WIRE 16 -1 (-1950 4025)(-1525 4025);
WIRE 16 -1 (-1525 4150)(-1525 4025);
WIRE 16 -1 (-1200 4025)(-1525 4025);
WIRE 16 -1 (-1200 4125)(-1200 4025);
WIRE 16 -1 (-1200 3975)(-1200 4025);
WIRE 16 -1 (-2550 4425)(-2300 4425);
WIRE 16 -1 (-2550 4425)(-3175 4425);
WIRE 16 -1 (-2550 4425)(-2550 3450);
WIRE 16 -1 (-2300 4425)(-1950 4425);
WIRE 16 -1 (-2300 4350)(-2300 4425);
WIRE 16 -1 (-1950 4425)(-1525 4425);
WIRE 16 -1 (-1950 4425)(-1950 4350);
WIRE 16 -1 (-2550 3450)(-3675 3450);
WIRE 16 -1 (-1200 4425)(-1525 4425);
WIRE 16 -1 (-1525 4425)(-1525 4350);
WIRE 16 -1 (-1200 4500)(-1200 4425);
WIRE 16 -1 (-1200 4425)(-1200 4325);
WIRE 16 -1 (-5650 4175)(-4900 4175);
WIRE 16 -1 (-4900 3450)(-4900 4175);
WIRE 16 -1 (-3875 3450)(-4900 3450);
FORCEPROP 2 LAST SIG_NAME PVDD11_S3_P0_VOS1
J 0
(-5510 4175);
DISPLAY 0.489362 (-5510 4175);
FORCEPROP 2 LASTPROP $XRERR UNIQUE?
J 0
(-5750 4175);
DISPLAY 0.638298 (-5750 4175);
PAINT MONO (-5750 4175);
DISPLAY INVISIBLE (-5750 4175);
WIRE 16 -1 (-5650 4775)(-4850 4775);
FORCEPROP 2 LAST SIG_NAME SW_PVDD11_S3_P0_BOOT1
J 0
(-5510 4785);
DISPLAY 0.489362 (-5510 4785);
FORCEPROP 2 LASTPROP $XRERR UNIQUE?
J 0
(-5750 4785);
DISPLAY 0.638298 (-5750 4785);
PAINT MONO (-5750 4785);
DISPLAY INVISIBLE (-5750 4785);
WIRE 16 -1 (-3925 4775)(-3925 4750);
WIRE 16 -1 (-4650 4775)(-3925 4775);
FORCEPROP 2 LAST SIG_NAME SW_PVDD11_S3_P0_BOOT1_RC
J 2
(-3960 4785);
DISPLAY 0.489362 (-3960 4785);
FORCEPROP 2 LASTPROP $XRERR UNIQUE?
J 0
(-4200 4785);
DISPLAY 0.638298 (-4200 4785);
PAINT MONO (-4200 4785);
DISPLAY INVISIBLE (-4200 4785);
WIRE 16 -1 (-5600 1850)(-4775 1850);
FORCEPROP 2 LAST SIG_NAME SW_PVDD11_S3_P0_BOOT2
J 0
(-5460 1860);
DISPLAY 0.489362 (-5460 1860);
FORCEPROP 2 LASTPROP $XRERR UNIQUE?
J 0
(-5700 1860);
DISPLAY 0.638298 (-5700 1860);
PAINT MONO (-5700 1860);
DISPLAY INVISIBLE (-5700 1860);
WIRE 16 -1 (-3850 1850)(-3850 1825);
WIRE 16 -1 (-4575 1850)(-3850 1850);
FORCEPROP 2 LAST SIG_NAME SW_PVDD11_S3_P0_BOOT2_RC
J 2
(-3885 1860);
DISPLAY 0.489362 (-3885 1860);
FORCEPROP 2 LASTPROP $XRERR UNIQUE?
J 0
(-4125 1860);
DISPLAY 0.638298 (-4125 1860);
PAINT MONO (-4125 1860);
DISPLAY INVISIBLE (-4125 1860);
WIRE 17 273 (-3025 2400)(-325 2400);
WIRE 17 273 (-3025 2400)(-3025 3325);
WIRE 17 273 (-325 3325)(-325 2400);
WIRE 17 273 (-3025 3325)(-325 3325);
WIRE 16 -1 (-8000 1400)(-7825 1400);
WIRE 16 -1 (-6450 1400)(-7825 1400);
FORCEPROP 2 LAST SIG_NAME PVDD11_S3_P0_VCCS
J 2
(-6535 1410);
DISPLAY 0.489362 (-6535 1410);
WIRE 16 -1 (-7825 1325)(-7825 1400);
WIRE 16 -1 (-6450 900)(-7050 900);
FORCEPROP 2 LAST SIG_NAME PVDD11_S3_P0_PWM2
J 2
(-6535 910);
DISPLAY 0.489362 (-6535 910);
WIRE 16 -1 (-6450 1250)(-6900 1250);
FORCEPROP 2 LAST SIG_NAME NC_PVDD11_S3_P0_DNC2
J 2
(-6535 1260);
DISPLAY 0.489362 (-6535 1260);
FORCEPROP 2 LASTPROP $XRERR UNIQUE?
J 0
(-7140 1250);
DISPLAY 0.638298 (-7140 1250);
PAINT MONO (-7140 1250);
DISPLAY INVISIBLE (-7140 1250);
WIRE 16 -1 (-6450 1000)(-7075 1000);
FORCEPROP 2 LAST SIG_NAME PVDD11_S3_P0_TEMP0
J 2
(-6535 1010);
DISPLAY 0.489362 (-6535 1010);
WIRE 16 -1 (-6450 1500)(-7100 1500);
FORCEPROP 2 LAST SIG_NAME PVDD11_S3_P0_IMON2
J 2
(-6535 1510);
DISPLAY 0.489362 (-6535 1510);
WIRE 16 -1 (-7775 2275)(-7775 2000);
WIRE 16 -1 (-7000 2000)(-7775 2000);
WIRE 16 -1 (-7775 2000)(-7775 1925);
WIRE 16 -1 (-7000 2000)(-7000 1850);
FORCEPROP 2 LAST SIG_NAME PVDD11_S3_P0_VCC2
J 2
(-6560 1860);
DISPLAY 0.489362 (-6560 1860);
FORCEPROP 2 LASTPROP $XRERR UNIQUE?
J 0
(-6800 1860);
DISPLAY 0.638298 (-6800 1860);
PAINT MONO (-6800 1860);
DISPLAY INVISIBLE (-6800 1860);
WIRE 16 -1 (-6450 1850)(-7000 1850);
WIRE 16 -1 (-7000 1850)(-7000 1650);
WIRE 16 -1 (-7000 1650)(-6450 1650);
WIRE 16 -1 (-5600 1150)(-5075 1150);
FORCEPROP 2 LAST SIG_NAME NC_PVDD11_S3_P0_GL2_2
J 0
(-5460 1160);
DISPLAY 0.489362 (-5460 1160);
FORCEPROP 2 LASTPROP $XRERR UNIQUE?
J 0
(-5045 1150);
DISPLAY 0.638298 (-5045 1150);
PAINT MONO (-5045 1150);
DISPLAY INVISIBLE (-5045 1150);
WIRE 16 -1 (-5600 1200)(-5075 1200);
FORCEPROP 2 LAST SIG_NAME NC_PVDD11_S3_P0_GL1_2
J 0
(-5460 1210);
DISPLAY 0.489362 (-5460 1210);
FORCEPROP 2 LASTPROP $XRERR UNIQUE?
J 0
(-5045 1200);
DISPLAY 0.638298 (-5045 1200);
PAINT MONO (-5045 1200);
DISPLAY INVISIBLE (-5045 1200);
WIRE 16 -1 (-4550 1400)(-4550 1500);
WIRE 16 -1 (-4550 1500)(-3475 1500);
WIRE 16 -1 (-5600 1500)(-4550 1500);
FORCEPROP 2 LAST SIG_NAME SW_PVDD11_S3_P0_SW2
J 0
(-5460 1510);
DISPLAY 0.489362 (-5460 1510);
FORCEPROP 2 LASTPROP $XRERR UNIQUE?
J 0
(-5700 1510);
DISPLAY 0.638298 (-5700 1510);
PAINT MONO (-5700 1510);
DISPLAY INVISIBLE (-5700 1510);
WIRE 16 -1 (-4550 1200)(-4550 925);
FORCEPROP 2 LAST SIG_NAME SW_PVDD11_S3_P0_SW2_RC
J 0
(-4510 1035);
DISPLAY 0.489362 (-4510 1035);
FORCEPROP 2 LASTPROP $XRERR UNIQUE?
J 0
(-4750 1035);
DISPLAY 0.638298 (-4750 1035);
PAINT MONO (-4750 1035);
DISPLAY INVISIBLE (-4750 1035);
WIRE 16 -1 (-5600 1250)(-4850 1250);
WIRE 16 -1 (-4850 550)(-4850 1250);
WIRE 16 -1 (-3550 550)(-4850 550);
FORCEPROP 2 LAST SIG_NAME PVDD11_S3_P0_VOS2
J 0
(-5460 1275);
DISPLAY 0.489362 (-5460 1275);
FORCEPROP 2 LASTPROP $XRERR UNIQUE?
J 0
(-5700 1275);
DISPLAY 0.638298 (-5700 1275);
PAINT MONO (-5700 1275);
DISPLAY INVISIBLE (-5700 1275);
WIRE 16 -1 (-4650 4125)(-4650 3850);
FORCEPROP 2 LAST SIG_NAME SW_PVDD11_S3_P0_SW1_RC
J 0
(-4610 3960);
DISPLAY 0.489362 (-4610 3960);
FORCEPROP 2 LASTPROP $XRERR UNIQUE?
J 0
(-4850 3960);
DISPLAY 0.638298 (-4850 3960);
PAINT MONO (-4850 3960);
DISPLAY INVISIBLE (-4850 3960);
WIRE 16 -1 (-8050 4325)(-7875 4325);
WIRE 16 -1 (-6500 4325)(-7875 4325);
FORCEPROP 2 LAST SIG_NAME PVDD11_S3_P0_VCCS
J 2
(-6585 4335);
DISPLAY 0.489362 (-6585 4335);
WIRE 16 -1 (-7875 4250)(-7875 4325);
WIRE 16 -1 (-6500 4425)(-7150 4425);
FORCEPROP 2 LAST SIG_NAME PVDD11_S3_P0_IMON1
J 2
(-6585 4435);
DISPLAY 0.489362 (-6585 4435);
WIRE 16 -1 (-6500 4175)(-6950 4175);
FORCEPROP 2 LAST SIG_NAME NC_PVDD11_S3_P0_DNC1
J 2
(-6585 4185);
DISPLAY 0.489362 (-6585 4185);
FORCEPROP 2 LASTPROP $XRERR UNIQUE?
J 0
(-7190 4175);
DISPLAY 0.638298 (-7190 4175);
PAINT MONO (-7190 4175);
DISPLAY INVISIBLE (-7190 4175);
WIRE 16 -1 (-7100 4125)(-6500 4125);
FORCEPROP 2 LAST SIG_NAME PVDD11_S3_P0_LSET1
J 2
(-6585 4135);
DISPLAY 0.489362 (-6585 4135);
FORCEPROP 2 LASTPROP $XRERR UNIQUE?
J 0
(-6825 4135);
DISPLAY 0.638298 (-6825 4135);
PAINT MONO (-6825 4135);
DISPLAY INVISIBLE (-6825 4135);
WIRE 16 -1 (-3850 1625)(-3850 1600);
WIRE 16 -1 (-3850 1600)(-5600 1600);
FORCEPROP 2 LAST SIG_NAME SW_PVDD11_S3_P0_PH2
J 0
(-5460 1610);
DISPLAY 0.489362 (-5460 1610);
FORCEPROP 2 LASTPROP $XRERR UNIQUE?
J 0
(-5700 1610);
DISPLAY 0.638298 (-5700 1610);
PAINT MONO (-5700 1610);
DISPLAY INVISIBLE (-5700 1610);
WIRE 16 -1 (-5650 4125)(-5125 4125);
FORCEPROP 2 LAST SIG_NAME NC_PVDD11_S3_P0_GL1_1
J 0
(-5510 4135);
DISPLAY 0.489362 (-5510 4135);
FORCEPROP 2 LASTPROP $XRERR UNIQUE?
J 0
(-5095 4125);
DISPLAY 0.638298 (-5095 4125);
PAINT MONO (-5095 4125);
DISPLAY INVISIBLE (-5095 4125);
WIRE 16 -1 (-5550 5500)(-5550 5075);
WIRE 16 -1 (-5550 5500)(-5375 5500);
WIRE 16 -1 (-5550 5075)(-5550 5025);
WIRE 16 -1 (-5650 5075)(-5550 5075);
WIRE 16 -1 (-5550 5025)(-5650 5025);
WIRE 16 -1 (-5375 5500)(-5050 5500);
WIRE 16 -1 (-5375 5425)(-5375 5500);
WIRE 16 -1 (-5050 5500)(-4750 5500);
WIRE 16 -1 (-5050 5425)(-5050 5500);
WIRE 16 -1 (-4425 5500)(-4750 5500);
WIRE 16 -1 (-4750 5425)(-4750 5500);
WIRE 16 -1 (-4200 5500)(-4425 5500);
WIRE 16 -1 (-4425 5500)(-4425 5425);
WIRE 16 -1 (-4000 5500)(-4200 5500);
WIRE 16 -1 (-4200 5500)(-4200 5425);
WIRE 16 -1 (-4000 5500)(-3900 5500);
WIRE 16 -1 (-4000 5425)(-4000 5500);
WIRE 16 -1 (-3800 5500)(-3900 5500);
WIRE 16 -1 (-3900 5625)(-3900 5500);
WIRE 16 -1 (-3550 5500)(-3800 5500);
WIRE 16 -1 (-3800 5500)(-3800 5425);
WIRE 16 -1 (-3250 5500)(-3550 5500);
WIRE 16 -1 (-3550 5425)(-3550 5500);
WIRE 16 -1 (-3000 5500)(-3250 5500);
WIRE 16 -1 (-3250 5425)(-3250 5500);
DOT 1 (-3550 5500);
DOT 1 (-4425 5500);
DOT 1 (-3550 5100);
DOT 1 (-3800 5500);
DOT 1 (-4000 5500);
DOT 1 (-3800 5100);
DOT 1 (-4000 5100);
DOT 1 (-4200 5100);
DOT 1 (-4200 5500);
DOT 1 (-4425 5100);
DOT 1 (-3250 5500);
DOT 1 (-1200 4425);
DOT 1 (-1525 4425);
DOT 1 (-1950 4425);
DOT 1 (-2300 4425);
DOT 1 (-2550 4425);
DOT 1 (-3900 5500);
DOT 1 (-3900 5100);
DOT 1 (-1200 4025);
DOT 1 (-1525 4025);
DOT 1 (-1950 4025);
DOT 1 (-1350 3025);
DOT 1 (-1050 3025);
DOT 1 (-1675 3025);
DOT 1 (-1050 2650);
DOT 1 (-1350 2650);
DOT 1 (-1675 2650);
DOT 1 (-1950 1500);
DOT 1 (-1950 1100);
DOT 1 (-2400 3025);
DOT 1 (-2725 3025);
DOT 1 (-2400 2625);
DOT 1 (-2725 2625);
DOT 1 (-4050 2575);
DOT 1 (-4050 2175);
DOT 1 (-2375 1500);
DOT 1 (-2625 1500);
DOT 1 (-5050 5500);
DOT 1 (-5050 5100);
DOT 1 (-5375 5500);
DOT 1 (-5550 5075);
DOT 1 (-7000 4775);
DOT 1 (-7425 5525);
DOT 1 (-7575 5525);
DOT 1 (-7775 5525);
DOT 1 (-8075 5525);
DOT 1 (-7775 4900);
DOT 1 (-7875 4325);
DOT 1 (-4375 2575);
DOT 1 (-4375 2175);
DOT 1 (-4675 2575);
DOT 1 (-5000 2575);
DOT 1 (-4675 2175);
DOT 1 (-5000 2175);
DOT 1 (-5425 3925);
DOT 1 (-5425 3875);
DOT 1 (-5425 3825);
DOT 1 (-5325 2575);
DOT 1 (-5475 2150);
DOT 1 (-4550 1500);
DOT 1 (-5425 1000);
DOT 1 (-5425 950);
DOT 1 (-5425 900);
DOT 1 (-7425 2600);
DOT 1 (-7775 2600);
DOT 1 (-7775 2000);
DOT 1 (-7000 1850);
DOT 1 (-7825 1400);
DOT 1 (-2275 5500);
DOT 1 (-4750 5100);
DOT 1 (-4750 5500);
DOT 1 (-4650 4425);
DOT 1 (-3700 2575);
DOT 1 (-3700 2175);
FORCENOTE
PVDD11_S3_P0_PHASE1
(-6625 5825) 0;
DISPLAY LEFT (-6625 5825);
DISPLAY 1.595745 (-6625 5825);
PAINT WHITE (-6625 5825);
FORCENOTE
PG2323.900HLT
(-3475 4175) 0;
DISPLAY LEFT (-3475 4175);
DISPLAY 0.638298 (-3475 4175);
PAINT WHITE (-3475 4175);
FORCENOTE
ISAT:132A@100C
(-3475 4125) 0;
DISPLAY LEFT (-3475 4125);
DISPLAY 0.638298 (-3475 4125);
PAINT WHITE (-3475 4125);
FORCENOTE
10.0*7.7*12.0
(-3475 4075) 0;
DISPLAY LEFT (-3475 4075);
DISPLAY 0.638298 (-3475 4075);
PAINT WHITE (-3475 4075);
FORCENOTE
DCR=0.103M OHM
(-3475 4025) 0;
DISPLAY LEFT (-3475 4025);
DISPLAY 0.638298 (-3475 4025);
PAINT WHITE (-3475 4025);
FORCENOTE
2ND=CVA90^0KZ04
(-3475 3975) 0;
DISPLAY LEFT (-3475 3975);
DISPLAY 0.638298 (-3475 3975);
PAINT WHITE (-3475 3975);
FORCENOTE
3RD=CVA90^0KZ08
(-3475 3925) 0;
DISPLAY LEFT (-3475 3925);
DISPLAY 0.638298 (-3475 3925);
PAINT WHITE (-3475 3925);
FORCENOTE
PU22,PU23 = AL087000A03/MP87000GMJTH-C11D-Z
(-9375 -25) 0;
DISPLAY LEFT (-9375 -25);
DISPLAY 1.021277 (-9375 -25);
PAINT WHITE (-9375 -25);
FORCENOTE
MAIN SOURCE:RENESAS BOM
(-9375 800) 0;
DISPLAY LEFT (-9375 800);
DISPLAY 1.276596 (-9375 800);
PAINT WHITE (-9375 800);
FORCENOTE
2ND SOURCE:INFENEON BOM
(-9375 525) 0;
DISPLAY LEFT (-9375 525);
DISPLAY 1.276596 (-9375 525);
PAINT WHITE (-9375 525);
FORCENOTE
PR133,PR134,PR135,PR136 = CS00002JB13
(-9375 375) 0;
DISPLAY LEFT (-9375 375);
DISPLAY 1.021277 (-9375 375);
PAINT WHITE (-9375 375);
FORCENOTE
PR413,PR135,PR136=CS00002JB13
(-9375 -100) 0;
DISPLAY LEFT (-9375 -100);
DISPLAY 1.021277 (-9375 -100);
PAINT WHITE (-9375 -100);
FORCENOTE
3RD SOURCE:MPS BOM
(-9375 50) 0;
DISPLAY LEFT (-9375 50);
DISPLAY 1.276596 (-9375 50);
PAINT WHITE (-9375 50);
FORCENOTE
PC201_1,PC202_2 = EMPTY
(-9375 225) 0;
DISPLAY LEFT (-9375 225);
DISPLAY 1.021277 (-9375 225);
PAINT WHITE (-9375 225);
FORCENOTE
PU22,PU23 = AL021590000/TDA21590
(-9375 450) 0;
DISPLAY LEFT (-9375 450);
DISPLAY 1.021277 (-9375 450);
PAINT WHITE (-9375 450);
FORCENOTE
PVDD11_S3_P0_PHASE2
(-6575 2900) 0;
DISPLAY LEFT (-6575 2900);
DISPLAY 1.595745 (-6575 2900);
PAINT WHITE (-6575 2900);
FORCENOTE
2ND=CC72703MD39
(-3425 4900) 0;
DISPLAY LEFT (-3425 4900);
DISPLAY 0.638298 (-3425 4900);
PAINT WHITE (-3425 4900);
FORCENOTE
6.3*8
(-3425 4950) 0;
DISPLAY LEFT (-3425 4950);
DISPLAY 0.638298 (-3425 4950);
PAINT WHITE (-3425 4950);
FORCENOTE
PG2289.101HLT
(-2975 5425) 0;
DISPLAY LEFT (-2975 5425);
DISPLAY 0.638298 (-2975 5425);
PAINT WHITE (-2975 5425);
FORCENOTE
3RD=CV+10G0MZ08
(-2975 5175) 0;
DISPLAY LEFT (-2975 5175);
DISPLAY 0.638298 (-2975 5175);
PAINT WHITE (-2975 5175);
FORCENOTE
ESR=10M OHM
(-3425 5050) 0;
DISPLAY LEFT (-3425 5050);
DISPLAY 0.638298 (-3425 5050);
PAINT WHITE (-3425 5050);
FORCENOTE
BOM NOTE
(-9375 925) 0;
DISPLAY LEFT (-9375 925);
DISPLAY 1.595745 (-9375 925);
PAINT WHITE (-9375 925);
FORCENOTE
PR411,PR137,PR138 = EMPTY
(-9375 -175) 0;
DISPLAY LEFT (-9375 -175);
DISPLAY 1.021277 (-9375 -175);
PAINT WHITE (-9375 -175);
FORCENOTE
PC201_1,PC202_2 = EMPTY
(-9375 -250) 0;
DISPLAY LEFT (-9375 -250);
DISPLAY 1.021277 (-9375 -250);
PAINT WHITE (-9375 -250);
FORCENOTE
PU22,PU23 = AL099390004/ISL99390FRZ-TR5935
(-9375 725) 0;
DISPLAY LEFT (-9375 725);
DISPLAY 1.021277 (-9375 725);
PAINT WHITE (-9375 725);
FORCENOTE
PR137,PR138 = EMPTY
(-9375 300) 0;
DISPLAY LEFT (-9375 300);
DISPLAY 1.021277 (-9375 300);
PAINT WHITE (-9375 300);
FORCENOTE
ESR=10M OHM
(-1500 2600) 0;
DISPLAY LEFT (-1500 2600);
DISPLAY 0.638298 (-1500 2600);
PAINT WHITE (-1500 2600);
FORCENOTE
5.0*5.8
(-1500 2550) 0;
DISPLAY LEFT (-1500 2550);
DISPLAY 0.638298 (-1500 2550);
PAINT WHITE (-1500 2550);
FORCENOTE
2ND=CC7390JMZ11
(-1500 2500) 0;
DISPLAY LEFT (-1500 2500);
DISPLAY 0.638298 (-1500 2500);
PAINT WHITE (-1500 2500);
FORCENOTE
7.3*4.3*1.9
(-2650 2500) 0;
DISPLAY LEFT (-2650 2500);
DISPLAY 0.638298 (-2650 2500);
PAINT WHITE (-2650 2500);
FORCENOTE
ESR=9M OHM
(-2650 2550) 0;
DISPLAY LEFT (-2650 2550);
DISPLAY 0.638298 (-2650 2550);
PAINT WHITE (-2650 2550);
FORCENOTE
2ND=CVA90^0KZ04
(-3475 1050) 0;
DISPLAY LEFT (-3475 1050);
DISPLAY 0.638298 (-3475 1050);
PAINT WHITE (-3475 1050);
FORCENOTE
3RD=CVA90^0KZ08
(-3475 1000) 0;
DISPLAY LEFT (-3475 1000);
DISPLAY 0.638298 (-3475 1000);
PAINT WHITE (-3475 1000);
FORCENOTE
PG2323.900HLT
(-3475 1250) 0;
DISPLAY LEFT (-3475 1250);
DISPLAY 0.638298 (-3475 1250);
PAINT WHITE (-3475 1250);
FORCENOTE
ISAT:132A@100C
(-3475 1200) 0;
DISPLAY LEFT (-3475 1200);
DISPLAY 0.638298 (-3475 1200);
PAINT WHITE (-3475 1200);
FORCENOTE
10.0*7.7*12.0
(-3475 1150) 0;
DISPLAY LEFT (-3475 1150);
DISPLAY 0.638298 (-3475 1150);
PAINT WHITE (-3475 1150);
FORCENOTE
DCR=0.103M OHM
(-3475 1100) 0;
DISPLAY LEFT (-3475 1100);
DISPLAY 0.638298 (-3475 1100);
PAINT WHITE (-3475 1100);
FORCENOTE
2ND=CV+10G0MZ04
(-2975 5225) 0;
DISPLAY LEFT (-2975 5225);
DISPLAY 0.638298 (-2975 5225);
PAINT WHITE (-2975 5225);
FORCENOTE
DCR:0.105M OHM
(-2975 5275) 0;
DISPLAY LEFT (-2975 5275);
DISPLAY 0.638298 (-2975 5275);
PAINT WHITE (-2975 5275);
FORCENOTE
4.5*4.7*4.5
(-2975 5325) 0;
DISPLAY LEFT (-2975 5325);
DISPLAY 0.638298 (-2975 5325);
PAINT WHITE (-2975 5325);
FORCENOTE
ISAT:13A@100C
(-2975 5375) 0;
DISPLAY LEFT (-2975 5375);
DISPLAY 0.638298 (-2975 5375);
PAINT WHITE (-2975 5375);
FORCENOTE
2ND=CH747LM8822
(-2650 2450) 0;
DISPLAY LEFT (-2650 2450);
DISPLAY 0.638298 (-2650 2450);
PAINT WHITE (-2650 2450);
FORCENOTE
IRIPPLE:5.08A
(-3425 5000) 0;
DISPLAY LEFT (-3425 5000);
DISPLAY 0.638298 (-3425 5000);
PAINT WHITE (-3425 5000);
QUIT
